FILE_TYPE = MACRO_DRAWING;
SET COLOR_WIRE YELLOW;
SET COLOR_PROP ORANGE;
SET COLOR_DOT WHITE;
SET COLOR_ARC YELLOW;
SET COLOR_BODY GREEN;
SET COLOR_NOTE PURPLE;
SET PROP_DISPLAY VALUE;
SET PAGE_NUMBER P324;
FORCEADD Q_RES..1
(-4100 -2400);
FORCEPROP 1 LAST PART_NUMBER CS00002JB13
J 0
(-4400 -2475);
DISPLAY 0.595745 (-4400 -2475);
DISPLAY INVISIBLE (-4400 -2475);
FORCEPROP 1 LAST TOLERANCE 5%
J 0
(-3925 -2400);
DISPLAY 0.595745 (-3925 -2400);
FORCEPROP 1 LAST VALUE 0
J 2
(-3950 -2400);
DISPLAY 0.595745 (-3950 -2400);
FORCEPROP 1 LAST PACK_TYPE 0402LF
J 0
(-4025 -2475);
DISPLAY 0.595745 (-4025 -2475);
FORCEPROP 1 LAST MATERIAL CHIP
J 0
(-4225 -2525);
DISPLAY 0.595745 (-4225 -2525);
FORCEPROP 1 LAST WATTAGE 1/16W
J 2
(-3900 -2525);
DISPLAY 0.595745 (-3900 -2525);
FORCEPROP 2 LAST ROOM E1S1_P3V3_BOM1
J 0
(-3900 -2375);
DISPLAY 0.638298 (-3900 -2375);
FORCEPROP 1 LAST $LOCATION R4063
J 0
(-4250 -2400);
DISPLAY 0.638298 (-4250 -2400);
FORCEPROP 2 LAST CDS_LIB pure_quanta
J 0
(-4100 -2400);
DISPLAY INVISIBLE (-4100 -2400);
FORCEPROP 1 LAST PATH I1
J 0
(-4150 -2250);
DISPLAY 0.978723 (-4150 -2250);
PAINT WHITE (-4150 -2250);
DISPLAY INVISIBLE (-4150 -2250);
FORCEPROP 0 LAST CDS_LOCATION R4063
J 0
(-4025 -2325);
DISPLAY INVISIBLE (-4025 -2325);
FORCEPROP 0 LAST $SEC 1
J 0
(-4025 -2325);
DISPLAY INVISIBLE (-4025 -2325);
FORCEPROP 0 LAST CDS_SEC 1
J 0
(-4025 -2325);
DISPLAY INVISIBLE (-4025 -2325);
FORCEPROP 1 LASTPIN (-4200 -2400) $PN 1
J 0
(-4188 -2388);
DISPLAY 0.787234 (-4188 -2388);
PAINT MONO (-4188 -2388);
DISPLAY INVISIBLE (-4188 -2388);
FORCEPROP 1 LASTPIN (-4000 -2400) $PN 2
J 0
(-4038 -2388);
DISPLAY 0.787234 (-4038 -2388);
PAINT MONO (-4038 -2388);
DISPLAY INVISIBLE (-4038 -2388);
FORCEADD MOSFET_NCH_DUAL..1
(-2575 150);
FORCEPROP 1 LAST PART_NUMBER BAM138K0003
J 0
(-2424 64);
DISPLAY 0.510638 (-2424 64);
PAINT GREEN (-2424 64);
DISPLAY INVISIBLE (-2424 64);
FORCEPROP 1 LAST MATERIAL EMPTY
J 0
(-2424 -1);
DISPLAY 0.510638 (-2424 -1);
PAINT RED (-2424 -1);
FORCEPROP 2 LAST VALUE PJT138K
J 0
(-2400 175);
DISPLAY 0.510638 (-2400 175);
FORCEPROP 2 LAST PART_TYPE SMLF
J 0
(-2400 225);
DISPLAY 0.510638 (-2400 225);
FORCEPROP 0 LAST ROOM E1S1_P12V_MAM_MAM_BOM1
J 0
(-2400 300);
DISPLAY 0.510638 (-2400 300);
FORCEPROP 1 LAST $LOCATION Q127
J 0
(-2424 124);
DISPLAY 0.510638 (-2424 124);
PAINT GREEN (-2424 124);
FORCEPROP 0 LASTPIN (-2525 350) $PN 6
R 1
J 0
(-2535 360);
DISPLAY 0.510638 (-2535 360);
PAINT MONO (-2535 360);
FORCEPROP 0 LASTPIN (-2775 100) $PN 2
J 2
(-2785 110);
DISPLAY 0.510638 (-2785 110);
PAINT MONO (-2785 110);
FORCEPROP 0 LASTPIN (-2525 -50) $PN 1
R 1
J 2
(-2535 -60);
DISPLAY 0.510638 (-2535 -60);
PAINT MONO (-2535 -60);
FORCEPROP 1 LAST NEEDS_NO_SIZE TRUE
J 0
(-2575 149);
DISPLAY 0.468085 (-2575 149);
PAINT GREEN (-2575 149);
DISPLAY INVISIBLE (-2575 149);
FORCEPROP 1 LAST CDS_LMAN_SYM_OUTLINE -150,150,150,-150
J 0
(-2575 150);
DISPLAY 0.468085 (-2575 150);
PAINT GREEN (-2575 150);
DISPLAY INVISIBLE (-2575 150);
FORCEPROP 2 LAST CDS_LIB pure_quanta
J 0
(-2575 150);
DISPLAY INVISIBLE (-2575 150);
FORCEPROP 0 LAST ROOM1 E1S1_P12V_MAM_TIC_BOM2
J 0
(-2400 400);
DISPLAY 1.021277 (-2400 400);
DISPLAY INVISIBLE (-2400 400);
FORCEPROP 1 LAST PATH I10
J 0
(-2575 150);
DISPLAY 0.723404 (-2575 150);
PAINT GREEN (-2575 150);
DISPLAY INVISIBLE (-2575 150);
FORCEPROP 0 LAST CDS_LOCATION Q127
J 0
(-2400 275);
DISPLAY 1.021277 (-2400 275);
DISPLAY INVISIBLE (-2400 275);
FORCEPROP 0 LAST $SEC 1
J 0
(-2400 275);
DISPLAY 0.680851 (-2400 275);
PAINT MONO (-2400 275);
DISPLAY INVISIBLE (-2400 275);
FORCEPROP 0 LAST CDS_SEC 1
J 0
(-2400 275);
DISPLAY 1.021277 (-2400 275);
DISPLAY INVISIBLE (-2400 275);
FORCEADD GND..1
(-2525 -200);
FORCEPROP 3 LASTPIN (-2525 -150) SIG_NAME GND\g
J 0
(-2515 -140);
DISPLAY 0.659574 (-2515 -140);
PAINT MONO (-2515 -140);
DISPLAY INVISIBLE (-2515 -140);
FORCEPROP 2 LAST CDS_LIB logical_power
J 0
(-2525 -200);
DISPLAY INVISIBLE (-2525 -200);
FORCEPROP 1 LAST SIZE 1B
J 0
(-2450 -250);
DISPLAY 0.872340 (-2450 -250);
PAINT GREEN (-2450 -250);
DISPLAY INVISIBLE (-2450 -250);
FORCEPROP 1 LAST HDL_POWER GND
J 0
(-2525 -50);
DISPLAY 0.872340 (-2525 -50);
PAINT GREEN (-2525 -50);
DISPLAY INVISIBLE (-2525 -50);
FORCEPROP 1 LAST PATH I11
J 0
(-2450 -200);
DISPLAY 0.872340 (-2450 -200);
PAINT AQUA (-2450 -200);
DISPLAY INVISIBLE (-2450 -200);
FORCEADD GND..1
(-125 -2600);
FORCEPROP 3 LASTPIN (-125 -2550) SIG_NAME GND\g
J 0
(-115 -2540);
DISPLAY 0.659574 (-115 -2540);
PAINT MONO (-115 -2540);
DISPLAY INVISIBLE (-115 -2540);
FORCEPROP 2 LAST CDS_LIB logical_power
J 0
(-125 -2600);
DISPLAY INVISIBLE (-125 -2600);
FORCEPROP 1 LAST SIZE 1B
J 0
(-50 -2650);
DISPLAY 0.872340 (-50 -2650);
PAINT GREEN (-50 -2650);
DISPLAY INVISIBLE (-50 -2650);
FORCEPROP 1 LAST HDL_POWER GND
J 0
(-125 -2450);
DISPLAY 0.872340 (-125 -2450);
PAINT GREEN (-125 -2450);
DISPLAY INVISIBLE (-125 -2450);
FORCEPROP 1 LAST PATH I12
J 0
(-50 -2600);
DISPLAY 0.872340 (-50 -2600);
PAINT AQUA (-50 -2600);
DISPLAY INVISIBLE (-50 -2600);
FORCEADD Q_RES..2
(-125 -2350);
FORCEPROP 1 LAST PART_NUMBER CS31502FB05
J 0
(-75 -2400);
DISPLAY 0.404255 (-75 -2400);
DISPLAY INVISIBLE (-75 -2400);
FORCEPROP 1 LAST TOLERANCE 1%
J 0
(-75 -2325);
DISPLAY 0.404255 (-75 -2325);
FORCEPROP 1 LAST VALUE 15K
J 0
(-75 -2300);
DISPLAY 0.404255 (-75 -2300);
FORCEPROP 1 LAST PACK_TYPE 0402LF
J 0
(-75 -2425);
DISPLAY 0.404255 (-75 -2425);
FORCEPROP 1 LAST WATTAGE 1/16W
J 0
(-75 -2350);
DISPLAY 0.404255 (-75 -2350);
FORCEPROP 1 LAST MATERIAL CHIP
J 0
(-75 -2375);
DISPLAY 0.404255 (-75 -2375);
FORCEPROP 2 LAST ROOM E1S1_P3V3_BOM1
J 0
(-50 -2475);
DISPLAY 0.638298 (-50 -2475);
FORCEPROP 1 LAST LOCATION PR3965
J 0
(-75 -2275);
DISPLAY 0.638298 (-75 -2275);
FORCEPROP 1 LASTPIN (-125 -2250) $PN 1
J 0
(-120 -2288);
DISPLAY 0.787234 (-120 -2288);
PAINT MONO (-120 -2288);
FORCEPROP 1 LASTPIN (-125 -2450) $PN 2
J 0
(-120 -2440);
DISPLAY 0.787234 (-120 -2440);
PAINT MONO (-120 -2440);
FORCEPROP 2 LAST CDS_LIB pure_quanta
J 0
(-125 -2350);
DISPLAY INVISIBLE (-125 -2350);
FORCEPROP 1 LAST PATH I13
J 0
(-75 -2175);
DISPLAY 0.978723 (-75 -2175);
PAINT WHITE (-75 -2175);
DISPLAY INVISIBLE (-75 -2175);
FORCEPROP 0 LAST $SEC 1
J 0
(-75 -2225);
DISPLAY 0.680851 (-75 -2225);
PAINT MONO (-75 -2225);
DISPLAY INVISIBLE (-75 -2225);
FORCEPROP 0 LAST CDS_SEC 1
J 0
(-75 -2225);
DISPLAY 1.021277 (-75 -2225);
DISPLAY INVISIBLE (-75 -2225);
FORCEADD Q_RES..2
(-125 -2075);
FORCEPROP 1 LAST PART_NUMBER CS27152FB03
J 0
(-75 -2125);
DISPLAY 0.404255 (-75 -2125);
DISPLAY INVISIBLE (-75 -2125);
FORCEPROP 1 LAST TOLERANCE 1%
J 0
(-75 -2050);
DISPLAY 0.404255 (-75 -2050);
FORCEPROP 1 LAST MATERIAL CHIP
J 0
(-75 -2100);
DISPLAY 0.404255 (-75 -2100);
FORCEPROP 1 LAST PACK_TYPE 0402LF
J 0
(-75 -2150);
DISPLAY 0.404255 (-75 -2150);
FORCEPROP 1 LAST WATTAGE 1/16W
J 0
(-75 -2075);
DISPLAY 0.404255 (-75 -2075);
FORCEPROP 1 LAST VALUE 7.15K
J 0
(-75 -2025);
DISPLAY 0.404255 (-75 -2025);
FORCEPROP 2 LAST ROOM E1S1_P3V3_BOM1
J 0
(-75 -1950);
DISPLAY 0.638298 (-75 -1950);
FORCEPROP 1 LAST LOCATION PR3964
J 0
(-75 -2000);
DISPLAY 0.638298 (-75 -2000);
FORCEPROP 1 LASTPIN (-125 -1975) $PN 1
J 0
(-120 -2013);
DISPLAY 0.787234 (-120 -2013);
PAINT MONO (-120 -2013);
FORCEPROP 1 LASTPIN (-125 -2175) $PN 2
J 0
(-120 -2165);
DISPLAY 0.787234 (-120 -2165);
PAINT MONO (-120 -2165);
FORCEPROP 2 LAST CDS_LIB pure_quanta
J 0
(-125 -2075);
DISPLAY INVISIBLE (-125 -2075);
FORCEPROP 1 LAST PATH I14
J 0
(-75 -1900);
DISPLAY 0.978723 (-75 -1900);
PAINT WHITE (-75 -1900);
DISPLAY INVISIBLE (-75 -1900);
FORCEPROP 0 LAST $SEC 1
J 0
(-75 -1950);
DISPLAY 0.680851 (-75 -1950);
PAINT MONO (-75 -1950);
DISPLAY INVISIBLE (-75 -1950);
FORCEPROP 0 LAST CDS_SEC 1
J 0
(-75 -1950);
DISPLAY 1.021277 (-75 -1950);
DISPLAY INVISIBLE (-75 -1950);
FORCEADD Q_RES..1
(-600 -1725);
FORCEPROP 1 LAST PART_NUMBER CS00002JB13
J 0
(-675 -1775);
DISPLAY 0.510638 (-675 -1775);
DISPLAY INVISIBLE (-675 -1775);
FORCEPROP 1 LAST WATTAGE 1/16W
J 2
(-425 -1825);
DISPLAY 0.510638 (-425 -1825);
FORCEPROP 1 LAST PACK_TYPE 0402LF
J 0
(-375 -1725);
DISPLAY 0.510638 (-375 -1725);
FORCEPROP 2 LAST ROOM E1S1_P3V3_BOM1
J 0
(-800 -1675);
DISPLAY 0.808511 (-800 -1675);
FORCEPROP 1 LAST TOLERANCE 5%
J 0
(-450 -1725);
DISPLAY 0.510638 (-450 -1725);
FORCEPROP 1 LAST VALUE 0
J 2
(-475 -1725);
DISPLAY 0.510638 (-475 -1725);
FORCEPROP 1 LAST MATERIAL CHIP
J 0
(-675 -1825);
DISPLAY 0.510638 (-675 -1825);
FORCEPROP 1 LAST $LOCATION R3959
J 0
(-800 -1725);
DISPLAY 0.638298 (-800 -1725);
FORCEPROP 1 LASTPIN (-700 -1725) $PN 1
J 0
(-688 -1713);
DISPLAY 0.787234 (-688 -1713);
PAINT MONO (-688 -1713);
FORCEPROP 1 LASTPIN (-500 -1725) $PN 2
J 0
(-538 -1713);
DISPLAY 0.787234 (-538 -1713);
PAINT MONO (-538 -1713);
FORCEPROP 2 LAST CDS_LIB pure_quanta
J 0
(-600 -1725);
DISPLAY INVISIBLE (-600 -1725);
FORCEPROP 1 LAST PATH I15
J 0
(-650 -1575);
DISPLAY 0.978723 (-650 -1575);
PAINT WHITE (-650 -1575);
DISPLAY INVISIBLE (-650 -1575);
FORCEPROP 0 LAST CDS_LOCATION R3959
J 0
(-650 -1625);
DISPLAY 1.021277 (-650 -1625);
DISPLAY INVISIBLE (-650 -1625);
FORCEPROP 0 LAST $SEC 1
J 0
(-650 -1625);
DISPLAY 0.680851 (-650 -1625);
PAINT MONO (-650 -1625);
DISPLAY INVISIBLE (-650 -1625);
FORCEPROP 0 LAST CDS_SEC 1
J 0
(-650 -1625);
DISPLAY 1.021277 (-650 -1625);
DISPLAY INVISIBLE (-650 -1625);
FORCEADD GND..1
(-475 -1375);
FORCEPROP 3 LASTPIN (-475 -1325) SIG_NAME GND\g
J 0
(-465 -1315);
DISPLAY 0.659574 (-465 -1315);
PAINT MONO (-465 -1315);
DISPLAY INVISIBLE (-465 -1315);
FORCEPROP 1 LAST SIZE 1B
J 0
(-400 -1425);
DISPLAY 0.872340 (-400 -1425);
PAINT GREEN (-400 -1425);
DISPLAY INVISIBLE (-400 -1425);
FORCEPROP 2 LAST CDS_LIB logical_power
J 0
(-475 -1375);
DISPLAY INVISIBLE (-475 -1375);
FORCEPROP 1 LAST HDL_POWER GND
J 0
(-475 -1225);
DISPLAY 0.872340 (-475 -1225);
PAINT GREEN (-475 -1225);
DISPLAY INVISIBLE (-475 -1225);
FORCEPROP 1 LAST PATH I16
J 0
(-400 -1375);
DISPLAY 0.872340 (-400 -1375);
PAINT AQUA (-400 -1375);
DISPLAY INVISIBLE (-400 -1375);
FORCEADD Q_CAP..1
(-475 -1100);
FORCEPROP 1 LAST PART_NUMBER CH5104KEB02
J 0
(-425 -1150);
DISPLAY 0.510638 (-425 -1150);
DISPLAY INVISIBLE (-425 -1150);
FORCEPROP 1 LAST VOLTAGE 25V
J 0
(-425 -1075);
DISPLAY 0.510638 (-425 -1075);
FORCEPROP 1 LAST VALUE 1UF
J 0
(-425 -1050);
DISPLAY 0.510638 (-425 -1050);
FORCEPROP 1 LAST MATERIAL X6S
J 0
(-425 -1100);
DISPLAY 0.510638 (-425 -1100);
FORCEPROP 1 LAST PACK_TYPE C0402
J 0
(-425 -1125);
DISPLAY 0.510638 (-425 -1125);
FORCEPROP 2 LAST ROOM E1S1_P3V3_BOM1
J 0
(-425 -975);
DISPLAY 0.510638 (-425 -975);
FORCEPROP 1 LAST LOCATION PC2208
J 0
(-425 -1025);
DISPLAY 0.638298 (-425 -1025);
FORCEPROP 1 LAST TOLERANCE 10%
J 0
(-425 -1150);
DISPLAY 0.638298 (-425 -1150);
DISPLAY INVISIBLE (-425 -1150);
FORCEPROP 2 LAST CDS_LIB pure_quanta
J 0
(-475 -1100);
DISPLAY INVISIBLE (-475 -1100);
FORCEPROP 1 LAST PATH I17
J 0
(-425 -950);
DISPLAY 0.978723 (-425 -950);
PAINT WHITE (-425 -950);
DISPLAY INVISIBLE (-425 -950);
FORCEPROP 0 LAST $SEC 1
J 0
(-420 -958);
DISPLAY INVISIBLE (-420 -958);
FORCEPROP 0 LAST CDS_SEC 1
J 0
(-420 -958);
DISPLAY INVISIBLE (-420 -958);
FORCEPROP 1 LASTPIN (-475 -1000) $PN 1
J 0
(-465 -1020);
DISPLAY 0.787234 (-465 -1020);
PAINT MONO (-465 -1020);
DISPLAY INVISIBLE (-465 -1020);
FORCEPROP 1 LASTPIN (-475 -1200) $PN 2
J 0
(-465 -1220);
DISPLAY 0.787234 (-465 -1220);
PAINT MONO (-465 -1220);
DISPLAY INVISIBLE (-465 -1220);
FORCEADD Q_RES..2
(-125 -1350);
FORCEPROP 1 LAST PART_NUMBER CS32552FB06
J 0
(-75 -1400);
DISPLAY 0.404255 (-75 -1400);
DISPLAY INVISIBLE (-75 -1400);
FORCEPROP 1 LAST MATERIAL CHIP
J 0
(-75 -1375);
DISPLAY 0.404255 (-75 -1375);
FORCEPROP 1 LAST WATTAGE 1/16W
J 0
(-75 -1350);
DISPLAY 0.404255 (-75 -1350);
FORCEPROP 1 LAST TOLERANCE 1%
J 0
(-75 -1325);
DISPLAY 0.404255 (-75 -1325);
FORCEPROP 1 LAST VALUE 25.5K
J 0
(-75 -1300);
DISPLAY 0.404255 (-75 -1300);
FORCEPROP 1 LAST PACK_TYPE 0402LF
J 0
(-75 -1425);
DISPLAY 0.404255 (-75 -1425);
FORCEPROP 2 LAST ROOM E1S1_P3V3_BOM1
J 0
(-75 -1225);
DISPLAY 0.404255 (-75 -1225);
FORCEPROP 1 LAST LOCATION PR3963
J 0
(-75 -1275);
DISPLAY 0.638298 (-75 -1275);
FORCEPROP 1 LASTPIN (-125 -1250) $PN 1
J 0
(-120 -1288);
DISPLAY 0.787234 (-120 -1288);
PAINT MONO (-120 -1288);
FORCEPROP 1 LASTPIN (-125 -1450) $PN 2
J 0
(-120 -1440);
DISPLAY 0.787234 (-120 -1440);
PAINT MONO (-120 -1440);
FORCEPROP 2 LAST CDS_LIB pure_quanta
J 0
(-125 -1350);
DISPLAY INVISIBLE (-125 -1350);
FORCEPROP 1 LAST PATH I18
J 0
(-75 -1175);
DISPLAY 0.978723 (-75 -1175);
PAINT WHITE (-75 -1175);
DISPLAY INVISIBLE (-75 -1175);
FORCEPROP 0 LAST $SEC 1
J 0
(-75 -1225);
DISPLAY 0.680851 (-75 -1225);
PAINT MONO (-75 -1225);
DISPLAY INVISIBLE (-75 -1225);
FORCEPROP 0 LAST CDS_SEC 1
J 0
(-75 -1225);
DISPLAY 1.021277 (-75 -1225);
DISPLAY INVISIBLE (-75 -1225);
FORCEADD UNIVERSAL_POWER..1
(-475 -750);
FORCEPROP 3 LASTPIN (-475 -800) SIG_NAME P3V3_AUX\g
J 0
(-465 -790);
DISPLAY 0.659574 (-465 -790);
PAINT MONO (-465 -790);
DISPLAY INVISIBLE (-465 -790);
FORCEPROP 1 LAST HDL_POWER P3V3_AUX
J 1
(-475 -700);
DISPLAY 0.872340 (-475 -700);
PAINT GREEN (-475 -700);
FORCEPROP 2 LAST CDS_LIB logical_power
J 0
(-475 -750);
DISPLAY INVISIBLE (-475 -750);
FORCEPROP 1 LAST PATH I19
J 0
(-425 -725);
DISPLAY 0.872340 (-425 -725);
PAINT AQUA (-425 -725);
DISPLAY INVISIBLE (-425 -725);
FORCEADD GND..1
(-3150 -2725);
FORCEPROP 3 LASTPIN (-3150 -2675) SIG_NAME GND\g
J 0
(-3140 -2665);
DISPLAY 0.659574 (-3140 -2665);
PAINT MONO (-3140 -2665);
DISPLAY INVISIBLE (-3140 -2665);
FORCEPROP 2 LAST CDS_LIB logical_power
J 0
(-3150 -2725);
DISPLAY INVISIBLE (-3150 -2725);
FORCEPROP 1 LAST SIZE 1B
J 0
(-3075 -2775);
DISPLAY 0.872340 (-3075 -2775);
PAINT GREEN (-3075 -2775);
DISPLAY INVISIBLE (-3075 -2775);
FORCEPROP 1 LAST HDL_POWER GND
J 0
(-3150 -2575);
DISPLAY 0.872340 (-3150 -2575);
PAINT GREEN (-3150 -2575);
DISPLAY INVISIBLE (-3150 -2575);
FORCEPROP 1 LAST PATH I2
J 0
(-3075 -2725);
DISPLAY 0.872340 (-3075 -2725);
PAINT AQUA (-3075 -2725);
DISPLAY INVISIBLE (-3075 -2725);
FORCEADD OFFPAGE..1
(-4450 100);
PAINT AQUA (-4450 100);
FORCEPROP 2 LAST $XR1 193 
J 0
(-4702 64);
DISPLAY 0.638298 (-4702 64);
PAINT MONO (-4702 64);
FORCEPROP 2 LAST $XR0 191 
J 0
(-4702 100);
DISPLAY 0.638298 (-4702 100);
PAINT MONO (-4702 100);
FORCEPROP 1 LAST OFFPAGE TRUE
J 0
(-4125 -25);
DISPLAY 0.872340 (-4125 -25);
PAINT AQUA (-4125 -25);
DISPLAY INVISIBLE (-4125 -25);
FORCEPROP 1 LAST COMMENT_BODY TRUE
J 0
(-4325 0);
DISPLAY 0.872340 (-4325 0);
PAINT GREEN (-4325 0);
DISPLAY INVISIBLE (-4325 0);
FORCEPROP 2 LAST CDS_LIB standard
J 0
(-4450 100);
DISPLAY INVISIBLE (-4450 100);
FORCEPROP 2 LAST PATH I20
J 0
(-4700 150);
DISPLAY 1.021277 (-4700 150);
DISPLAY INVISIBLE (-4700 150);
FORCEADD Q_RES..1
(-3400 100);
FORCEPROP 1 LAST PART_NUMBER CS00002JB13
J 0
(-3700 25);
DISPLAY 0.510638 (-3700 25);
DISPLAY INVISIBLE (-3700 25);
FORCEPROP 1 LAST MATERIAL CHIP
J 0
(-3525 -25);
DISPLAY 0.510638 (-3525 -25);
FORCEPROP 1 LAST PACK_TYPE 0402LF
J 0
(-3325 25);
DISPLAY 0.510638 (-3325 25);
FORCEPROP 1 LAST WATTAGE 1/16W
J 2
(-3200 -25);
DISPLAY 0.510638 (-3200 -25);
FORCEPROP 1 LAST TOLERANCE 5%
J 0
(-3225 100);
DISPLAY 0.510638 (-3225 100);
FORCEPROP 1 LAST VALUE 0
J 2
(-3250 100);
DISPLAY 0.510638 (-3250 100);
FORCEPROP 1 LAST $LOCATION R4064
J 0
(-3625 100);
DISPLAY 0.510638 (-3625 100);
FORCEPROP 2 LAST CDS_LIB pure_quanta
J 0
(-3400 100);
DISPLAY INVISIBLE (-3400 100);
FORCEPROP 1 LAST PATH I21
J 0
(-3450 250);
DISPLAY 0.978723 (-3450 250);
PAINT WHITE (-3450 250);
DISPLAY INVISIBLE (-3450 250);
FORCEPROP 0 LAST CDS_LOCATION R4064
J 0
(-3325 175);
DISPLAY INVISIBLE (-3325 175);
FORCEPROP 0 LAST $SEC 1
J 0
(-3325 175);
DISPLAY INVISIBLE (-3325 175);
FORCEPROP 0 LAST CDS_SEC 1
J 0
(-3325 175);
DISPLAY INVISIBLE (-3325 175);
FORCEPROP 1 LASTPIN (-3500 100) $PN 1
J 0
(-3488 112);
DISPLAY 0.787234 (-3488 112);
PAINT MONO (-3488 112);
DISPLAY INVISIBLE (-3488 112);
FORCEPROP 1 LASTPIN (-3300 100) $PN 2
J 0
(-3338 112);
DISPLAY 0.787234 (-3338 112);
PAINT MONO (-3338 112);
DISPLAY INVISIBLE (-3338 112);
FORCEADD Q_RES..2
(-2525 750);
FORCEPROP 1 LAST PART_NUMBER CS31002FB08
J 0
(-2495 667);
DISPLAY 0.510638 (-2495 667);
DISPLAY INVISIBLE (-2495 667);
FORCEPROP 2 LAST ROOM E1S1_P12V_MAM_MAM_BOM1
J 0
(-2475 950);
DISPLAY 0.510638 (-2475 950);
FORCEPROP 1 LAST TOLERANCE 1%
J 0
(-2490 817);
DISPLAY 0.510638 (-2490 817);
FORCEPROP 1 LAST VALUE 10K
J 0
(-2490 867);
DISPLAY 0.510638 (-2490 867);
FORCEPROP 1 LAST WATTAGE 1/16W
J 0
(-2495 767);
DISPLAY 0.510638 (-2495 767);
FORCEPROP 1 LAST PACK_TYPE 0402LF
J 0
(-2495 617);
DISPLAY 0.510638 (-2495 617);
FORCEPROP 1 LAST MATERIAL EMPTY
J 0
(-2495 717);
DISPLAY 0.510638 (-2495 717);
PAINT RED (-2495 717);
FORCEPROP 1 LAST $LOCATION R4074
J 0
(-2490 917);
DISPLAY 0.510638 (-2490 917);
FORCEPROP 1 LASTPIN (-2525 850) $PN 1
J 0
(-2520 812);
DISPLAY 0.510638 (-2520 812);
PAINT MONO (-2520 812);
FORCEPROP 1 LASTPIN (-2525 650) $PN 2
J 0
(-2520 660);
DISPLAY 0.510638 (-2520 660);
PAINT MONO (-2520 660);
FORCEPROP 2 LAST ROOM1 E1S1_P12V_MAM_TIC_BOM2
J 0
(-2475 1000);
DISPLAY 1.021277 (-2475 1000);
DISPLAY INVISIBLE (-2475 1000);
FORCEPROP 2 LAST CDS_LIB pure_quanta
J 0
(-2525 750);
DISPLAY INVISIBLE (-2525 750);
FORCEPROP 1 LAST PATH I22
J 0
(-2475 925);
DISPLAY 0.978723 (-2475 925);
PAINT WHITE (-2475 925);
DISPLAY INVISIBLE (-2475 925);
FORCEPROP 0 LAST CDS_LOCATION R4074
J 0
(-2475 950);
DISPLAY 1.021277 (-2475 950);
DISPLAY INVISIBLE (-2475 950);
FORCEPROP 0 LAST $SEC 1
J 0
(-2475 950);
DISPLAY 0.680851 (-2475 950);
PAINT MONO (-2475 950);
DISPLAY INVISIBLE (-2475 950);
FORCEPROP 0 LAST CDS_SEC 1
J 0
(-2475 950);
DISPLAY 1.021277 (-2475 950);
DISPLAY INVISIBLE (-2475 950);
FORCEADD UNIVERSAL_POWER..1
(-2525 1000);
FORCEPROP 3 LASTPIN (-2525 950) SIG_NAME P12V_AUX\g
J 0
(-2515 960);
DISPLAY 0.659574 (-2515 960);
PAINT MONO (-2515 960);
DISPLAY INVISIBLE (-2515 960);
FORCEPROP 1 LAST HDL_POWER P12V_AUX
J 1
(-2525 1050);
DISPLAY 0.510638 (-2525 1050);
PAINT GREEN (-2525 1050);
FORCEPROP 2 LAST CDS_LIB logical_power
J 0
(-2525 1000);
DISPLAY INVISIBLE (-2525 1000);
FORCEPROP 1 LAST PATH I23
J 0
(-2475 1025);
DISPLAY 0.872340 (-2475 1025);
PAINT AQUA (-2475 1025);
DISPLAY INVISIBLE (-2475 1025);
FORCEADD MOSFET_NCH_DUAL..2
(-1875 525);
FORCEPROP 1 LAST PART_NUMBER BAM138K0003
J 0
(-1724 431);
DISPLAY 0.510638 (-1724 431);
PAINT GREEN (-1724 431);
DISPLAY INVISIBLE (-1724 431);
FORCEPROP 1 LAST MATERIAL EMPTY
J 0
(-1724 376);
DISPLAY 0.510638 (-1724 376);
PAINT RED (-1724 376);
FORCEPROP 2 LAST VALUE PJT138K
J 0
(-1700 550);
DISPLAY 0.510638 (-1700 550);
FORCEPROP 2 LAST PART_TYPE SMLF
J 0
(-1700 600);
DISPLAY 0.510638 (-1700 600);
FORCEPROP 2 LAST ROOM E1S1_P12V_MAM_MAM_BOM1
J 0
(-1700 650);
DISPLAY 0.510638 (-1700 650);
FORCEPROP 1 LAST $LOCATION Q127
J 0
(-1724 501);
DISPLAY 0.510638 (-1724 501);
PAINT GREEN (-1724 501);
FORCEPROP 0 LASTPIN (-1825 725) $PN 3
R 1
J 0
(-1835 735);
DISPLAY 0.510638 (-1835 735);
PAINT MONO (-1835 735);
FORCEPROP 0 LASTPIN (-2075 475) $PN 5
J 2
(-2085 485);
DISPLAY 0.510638 (-2085 485);
PAINT MONO (-2085 485);
FORCEPROP 0 LASTPIN (-1825 325) $PN 4
R 1
J 2
(-1835 315);
DISPLAY 0.510638 (-1835 315);
PAINT MONO (-1835 315);
FORCEPROP 2 LAST ROOM1 E1S1_P12V_MAM_TIC_BOM2
J 0
(-1700 700);
DISPLAY 1.021277 (-1700 700);
DISPLAY INVISIBLE (-1700 700);
FORCEPROP 1 LAST NEEDS_NO_SIZE TRUE
J 0
(-1725 416);
DISPLAY 0.468085 (-1725 416);
PAINT GREEN (-1725 416);
DISPLAY INVISIBLE (-1725 416);
FORCEPROP 1 LAST CDS_LMAN_SYM_OUTLINE -150,150,150,-150
J 0
(-1875 525);
DISPLAY 0.468085 (-1875 525);
PAINT GREEN (-1875 525);
DISPLAY INVISIBLE (-1875 525);
FORCEPROP 2 LAST CDS_LIB pure_quanta
J 0
(-1875 525);
DISPLAY INVISIBLE (-1875 525);
FORCEPROP 1 LAST PATH I24
J 0
(-1725 375);
DISPLAY 0.723404 (-1725 375);
PAINT GREEN (-1725 375);
DISPLAY INVISIBLE (-1725 375);
FORCEPROP 0 LAST CDS_LOCATION Q127
J 0
(-1700 650);
DISPLAY 1.021277 (-1700 650);
DISPLAY INVISIBLE (-1700 650);
FORCEPROP 0 LAST $SEC 2
J 0
(-1700 650);
DISPLAY 0.680851 (-1700 650);
PAINT MONO (-1700 650);
DISPLAY INVISIBLE (-1700 650);
FORCEPROP 0 LAST CDS_SEC 2
J 0
(-1700 650);
DISPLAY 1.021277 (-1700 650);
DISPLAY INVISIBLE (-1700 650);
FORCEADD GND..1
(-1825 175);
FORCEPROP 3 LASTPIN (-1825 225) SIG_NAME GND\g
J 0
(-1815 235);
DISPLAY 0.659574 (-1815 235);
PAINT MONO (-1815 235);
DISPLAY INVISIBLE (-1815 235);
FORCEPROP 2 LAST CDS_LIB logical_power
J 0
(-1825 175);
DISPLAY INVISIBLE (-1825 175);
FORCEPROP 1 LAST SIZE 1B
J 0
(-1750 125);
DISPLAY 0.872340 (-1750 125);
PAINT GREEN (-1750 125);
DISPLAY INVISIBLE (-1750 125);
FORCEPROP 1 LAST HDL_POWER GND
J 0
(-1825 325);
DISPLAY 0.872340 (-1825 325);
PAINT GREEN (-1825 325);
DISPLAY INVISIBLE (-1825 325);
FORCEPROP 1 LAST PATH I25
J 0
(-1750 175);
DISPLAY 0.872340 (-1750 175);
PAINT AQUA (-1750 175);
DISPLAY INVISIBLE (-1750 175);
FORCEADD Q_RES..1
(-750 1000);
FORCEPROP 1 LAST PART_NUMBER CS00002JB13
J 0
(-825 950);
DISPLAY 0.510638 (-825 950);
DISPLAY INVISIBLE (-825 950);
FORCEPROP 1 LAST WATTAGE 1/16W
J 2
(-550 900);
DISPLAY 0.510638 (-550 900);
FORCEPROP 1 LAST MATERIAL EMPTY
J 0
(-825 900);
DISPLAY 0.510638 (-825 900);
PAINT RED (-825 900);
FORCEPROP 1 LAST VALUE 0
J 2
(-600 1000);
DISPLAY 0.510638 (-600 1000);
FORCEPROP 1 LAST TOLERANCE 5%
J 0
(-575 1000);
DISPLAY 0.510638 (-575 1000);
FORCEPROP 1 LAST PACK_TYPE 0402LF
J 0
(-475 1000);
DISPLAY 0.510638 (-475 1000);
FORCEPROP 2 LAST ROOM E1S1_P12V_MAM_MAM_BOM1
J 0
(-800 1100);
DISPLAY 0.510638 (-800 1100);
FORCEPROP 1 LAST $LOCATION R3958
J 0
(-800 1050);
DISPLAY 0.510638 (-800 1050);
FORCEPROP 1 LASTPIN (-850 1000) $PN 1
J 0
(-838 1012);
DISPLAY 0.510638 (-838 1012);
PAINT MONO (-838 1012);
FORCEPROP 1 LASTPIN (-650 1000) $PN 2
J 0
(-688 1012);
DISPLAY 0.510638 (-688 1012);
PAINT MONO (-688 1012);
FORCEPROP 2 LAST ROOM1 E1S1_P12V_MAM_TIC_BOM2
J 0
(-800 1150);
DISPLAY 1.021277 (-800 1150);
DISPLAY INVISIBLE (-800 1150);
FORCEPROP 2 LAST CDS_LIB pure_quanta
J 0
(-750 1000);
DISPLAY INVISIBLE (-750 1000);
FORCEPROP 1 LAST PATH I26
J 0
(-800 1150);
DISPLAY 0.978723 (-800 1150);
PAINT WHITE (-800 1150);
DISPLAY INVISIBLE (-800 1150);
FORCEPROP 0 LAST CDS_LOCATION R3958
J 0
(-800 1100);
DISPLAY 1.021277 (-800 1100);
DISPLAY INVISIBLE (-800 1100);
FORCEPROP 0 LAST $SEC 1
J 0
(-800 1100);
DISPLAY 0.680851 (-800 1100);
PAINT MONO (-800 1100);
DISPLAY INVISIBLE (-800 1100);
FORCEPROP 0 LAST CDS_SEC 1
J 0
(-800 1100);
DISPLAY 1.021277 (-800 1100);
DISPLAY INVISIBLE (-800 1100);
FORCEADD GND..1
(-150 125);
FORCEPROP 3 LASTPIN (-150 175) SIG_NAME GND\g
J 0
(-140 185);
DISPLAY 0.659574 (-140 185);
PAINT MONO (-140 185);
DISPLAY INVISIBLE (-140 185);
FORCEPROP 2 LAST CDS_LIB logical_power
J 0
(-150 125);
DISPLAY INVISIBLE (-150 125);
FORCEPROP 1 LAST SIZE 1B
J 0
(-75 75);
DISPLAY 0.872340 (-75 75);
PAINT GREEN (-75 75);
DISPLAY INVISIBLE (-75 75);
FORCEPROP 1 LAST HDL_POWER GND
J 0
(-150 275);
DISPLAY 0.872340 (-150 275);
PAINT GREEN (-150 275);
DISPLAY INVISIBLE (-150 275);
FORCEPROP 1 LAST PATH I27
J 0
(-75 125);
DISPLAY 0.872340 (-75 125);
PAINT AQUA (-75 125);
DISPLAY INVISIBLE (-75 125);
FORCEADD Q_RES..2
(-150 375);
FORCEPROP 1 LAST PART_NUMBER CS31502FB05
J 0
(-100 325);
DISPLAY 0.510638 (-100 325);
DISPLAY INVISIBLE (-100 325);
FORCEPROP 1 LAST WATTAGE 1/16W
J 0
(-100 375);
DISPLAY 0.510638 (-100 375);
FORCEPROP 1 LAST TOLERANCE 1%
J 0
(-100 400);
DISPLAY 0.510638 (-100 400);
FORCEPROP 1 LAST VALUE 15K
J 0
(-100 425);
DISPLAY 0.510638 (-100 425);
FORCEPROP 1 LAST PACK_TYPE 0402LF
J 0
(-100 300);
DISPLAY 0.510638 (-100 300);
FORCEPROP 2 LAST ROOM E1S1_P12V_MAM_MAM_BOM1
J 0
(-100 275);
DISPLAY 0.510638 (-100 275);
FORCEPROP 1 LAST MATERIAL EMPTY
J 0
(-100 350);
DISPLAY 0.510638 (-100 350);
PAINT RED (-100 350);
FORCEPROP 1 LAST LOCATION PR3962
J 0
(-100 450);
DISPLAY 0.510638 (-100 450);
FORCEPROP 1 LASTPIN (-150 475) $PN 1
J 0
(-145 437);
DISPLAY 0.510638 (-145 437);
PAINT MONO (-145 437);
FORCEPROP 1 LASTPIN (-150 275) $PN 2
J 0
(-145 285);
DISPLAY 0.510638 (-145 285);
PAINT MONO (-145 285);
FORCEPROP 2 LAST ROOM1 E1S1_P12V_MAM_TIC_BOM2
J 0
(-100 550);
DISPLAY 1.021277 (-100 550);
DISPLAY INVISIBLE (-100 550);
FORCEPROP 2 LAST CDS_LIB pure_quanta
J 0
(-150 375);
DISPLAY INVISIBLE (-150 375);
FORCEPROP 1 LAST PATH I28
J 0
(-100 550);
DISPLAY 0.978723 (-100 550);
PAINT WHITE (-100 550);
DISPLAY INVISIBLE (-100 550);
FORCEPROP 0 LAST $SEC 1
J 0
(-100 500);
DISPLAY 0.680851 (-100 500);
PAINT MONO (-100 500);
DISPLAY INVISIBLE (-100 500);
FORCEPROP 0 LAST CDS_SEC 1
J 0
(-100 500);
DISPLAY 1.021277 (-100 500);
DISPLAY INVISIBLE (-100 500);
FORCEADD GND..1
(-725 1250);
FORCEPROP 3 LASTPIN (-725 1300) SIG_NAME GND\g
J 0
(-715 1310);
DISPLAY 0.659574 (-715 1310);
PAINT MONO (-715 1310);
DISPLAY INVISIBLE (-715 1310);
FORCEPROP 1 LAST SIZE 1B
J 0
(-650 1200);
DISPLAY 0.872340 (-650 1200);
PAINT GREEN (-650 1200);
DISPLAY INVISIBLE (-650 1200);
FORCEPROP 2 LAST CDS_LIB logical_power
J 0
(-725 1250);
DISPLAY INVISIBLE (-725 1250);
FORCEPROP 1 LAST HDL_POWER GND
J 0
(-725 1400);
DISPLAY 0.872340 (-725 1400);
PAINT GREEN (-725 1400);
DISPLAY INVISIBLE (-725 1400);
FORCEPROP 1 LAST PATH I29
J 0
(-650 1250);
DISPLAY 0.872340 (-650 1250);
PAINT AQUA (-650 1250);
DISPLAY INVISIBLE (-650 1250);
FORCEADD MOSFET_NCH_DUAL..1
(-3200 -2375);
FORCEPROP 1 LAST PART_NUMBER BAM138K0003
J 0
(-3049 -2461);
DISPLAY 0.723404 (-3049 -2461);
PAINT GREEN (-3049 -2461);
DISPLAY INVISIBLE (-3049 -2461);
FORCEPROP 1 LAST MATERIAL IC
J 0
(-3049 -2526);
DISPLAY 0.723404 (-3049 -2526);
PAINT GREEN (-3049 -2526);
FORCEPROP 2 LAST ROOM E1S1_P3V3_BOM1
J 0
(-3025 -2250);
DISPLAY 0.808511 (-3025 -2250);
FORCEPROP 2 LAST PART_TYPE SMLF
J 0
(-3025 -2300);
DISPLAY 1.021277 (-3025 -2300);
FORCEPROP 2 LAST VALUE PJT138K
J 0
(-3025 -2350);
DISPLAY 1.021277 (-3025 -2350);
FORCEPROP 1 LAST $LOCATION Q126
J 0
(-3049 -2401);
DISPLAY 0.723404 (-3049 -2401);
PAINT GREEN (-3049 -2401);
FORCEPROP 0 LASTPIN (-3150 -2175) $PN 6
R 1
J 0
(-3160 -2165);
DISPLAY 0.680851 (-3160 -2165);
PAINT MONO (-3160 -2165);
FORCEPROP 0 LASTPIN (-3400 -2425) $PN 2
J 2
(-3410 -2415);
DISPLAY 0.680851 (-3410 -2415);
PAINT MONO (-3410 -2415);
FORCEPROP 0 LASTPIN (-3150 -2575) $PN 1
R 1
J 2
(-3160 -2585);
DISPLAY 0.680851 (-3160 -2585);
PAINT MONO (-3160 -2585);
FORCEPROP 2 LAST CDS_LIB pure_quanta
J 0
(-3200 -2375);
DISPLAY INVISIBLE (-3200 -2375);
FORCEPROP 1 LAST CDS_LMAN_SYM_OUTLINE -150,150,150,-150
J 0
(-3200 -2375);
DISPLAY 0.468085 (-3200 -2375);
PAINT GREEN (-3200 -2375);
DISPLAY INVISIBLE (-3200 -2375);
FORCEPROP 1 LAST NEEDS_NO_SIZE TRUE
J 0
(-3200 -2376);
DISPLAY 0.468085 (-3200 -2376);
PAINT GREEN (-3200 -2376);
DISPLAY INVISIBLE (-3200 -2376);
FORCEPROP 1 LAST PATH I3
J 0
(-3200 -2375);
DISPLAY 0.723404 (-3200 -2375);
PAINT GREEN (-3200 -2375);
DISPLAY INVISIBLE (-3200 -2375);
FORCEPROP 0 LAST CDS_LOCATION Q126
J 0
(-3025 -2250);
DISPLAY 1.021277 (-3025 -2250);
DISPLAY INVISIBLE (-3025 -2250);
FORCEPROP 0 LAST $SEC 1
J 0
(-3025 -2250);
DISPLAY 0.680851 (-3025 -2250);
PAINT MONO (-3025 -2250);
DISPLAY INVISIBLE (-3025 -2250);
FORCEPROP 0 LAST CDS_SEC 1
J 0
(-3025 -2250);
DISPLAY 1.021277 (-3025 -2250);
DISPLAY INVISIBLE (-3025 -2250);
FORCEADD UNIVERSAL_POWER..1
(-725 1975);
FORCEPROP 3 LASTPIN (-725 1925) SIG_NAME P12V_AUX\g
J 0
(-715 1935);
DISPLAY 0.659574 (-715 1935);
PAINT MONO (-715 1935);
DISPLAY INVISIBLE (-715 1935);
FORCEPROP 1 LAST HDL_POWER P12V_AUX
J 1
(-725 2025);
DISPLAY 0.510638 (-725 2025);
PAINT GREEN (-725 2025);
FORCEPROP 2 LAST CDS_LIB logical_power
J 0
(-725 1975);
DISPLAY INVISIBLE (-725 1975);
FORCEPROP 1 LAST PATH I30
J 0
(-675 2000);
DISPLAY 0.872340 (-675 2000);
PAINT AQUA (-675 2000);
DISPLAY INVISIBLE (-675 2000);
FORCEADD Q_CAP..1
(-500 1625);
FORCEPROP 1 LAST PART_NUMBER CH5104KEB02
J 0
(-450 1575);
DISPLAY 0.510638 (-450 1575);
DISPLAY INVISIBLE (-450 1575);
FORCEPROP 1 LAST PACK_TYPE C0402
J 0
(-450 1600);
DISPLAY 0.510638 (-450 1600);
FORCEPROP 1 LAST VOLTAGE 25V
J 0
(-450 1650);
DISPLAY 0.510638 (-450 1650);
FORCEPROP 1 LAST VALUE 1UF
J 0
(-450 1675);
DISPLAY 0.510638 (-450 1675);
FORCEPROP 1 LAST MATERIAL X6S
J 0
(-450 1625);
DISPLAY 0.510638 (-450 1625);
FORCEPROP 1 LAST LOCATION PC2207
J 0
(-450 1700);
DISPLAY 0.510638 (-450 1700);
FORCEPROP 2 LAST CDS_LIB pure_quanta
J 0
(-500 1625);
DISPLAY INVISIBLE (-500 1625);
FORCEPROP 1 LAST TOLERANCE 10%
J 0
(-450 1575);
DISPLAY 0.638298 (-450 1575);
DISPLAY INVISIBLE (-450 1575);
FORCEPROP 1 LAST PATH I31
J 0
(-450 1775);
DISPLAY 0.978723 (-450 1775);
PAINT WHITE (-450 1775);
DISPLAY INVISIBLE (-450 1775);
FORCEPROP 0 LAST $SEC 1
J 0
(-445 1767);
DISPLAY INVISIBLE (-445 1767);
FORCEPROP 0 LAST CDS_SEC 1
J 0
(-445 1767);
DISPLAY INVISIBLE (-445 1767);
FORCEPROP 1 LASTPIN (-500 1725) $PN 1
J 0
(-490 1705);
DISPLAY 0.787234 (-490 1705);
PAINT MONO (-490 1705);
DISPLAY INVISIBLE (-490 1705);
FORCEPROP 1 LASTPIN (-500 1525) $PN 2
J 0
(-490 1505);
DISPLAY 0.787234 (-490 1505);
PAINT MONO (-490 1505);
DISPLAY INVISIBLE (-490 1505);
FORCEADD Q_RES..2
(-150 1325);
FORCEPROP 1 LAST PART_NUMBER CS41602FB05
J 0
(-100 1275);
DISPLAY 0.510638 (-100 1275);
DISPLAY INVISIBLE (-100 1275);
FORCEPROP 1 LAST VALUE 160K
J 0
(-100 1375);
DISPLAY 0.510638 (-100 1375);
FORCEPROP 1 LAST TOLERANCE 1%
J 0
(-100 1350);
DISPLAY 0.510638 (-100 1350);
FORCEPROP 1 LAST PACK_TYPE 0402LF
J 0
(-100 1250);
DISPLAY 0.510638 (-100 1250);
FORCEPROP 1 LAST MATERIAL EMPTY
J 0
(-100 1300);
DISPLAY 0.510638 (-100 1300);
PAINT RED (-100 1300);
FORCEPROP 1 LAST WATTAGE 1/16W
J 0
(-100 1325);
DISPLAY 0.510638 (-100 1325);
FORCEPROP 2 LAST ROOM E1S1_P12V_MAM_MAM_BOM1
J 0
(-100 1450);
DISPLAY 0.510638 (-100 1450);
FORCEPROP 1 LAST LOCATION PR3960
J 0
(-100 1400);
DISPLAY 0.510638 (-100 1400);
FORCEPROP 1 LASTPIN (-150 1425) $PN 1
J 0
(-145 1387);
DISPLAY 0.510638 (-145 1387);
PAINT MONO (-145 1387);
FORCEPROP 1 LASTPIN (-150 1225) $PN 2
J 0
(-145 1235);
DISPLAY 0.510638 (-145 1235);
PAINT MONO (-145 1235);
FORCEPROP 2 LAST ROOM1 E1S1_P12V_MAM_TIC_BOM2
J 0
(-100 1500);
DISPLAY 1.021277 (-100 1500);
DISPLAY INVISIBLE (-100 1500);
FORCEPROP 2 LAST CDS_LIB pure_quanta
J 0
(-150 1325);
DISPLAY INVISIBLE (-150 1325);
FORCEPROP 1 LAST PATH I32
J 0
(-100 1500);
DISPLAY 0.978723 (-100 1500);
PAINT WHITE (-100 1500);
DISPLAY INVISIBLE (-100 1500);
FORCEPROP 0 LAST $SEC 1
J 0
(-100 1450);
DISPLAY 0.680851 (-100 1450);
PAINT MONO (-100 1450);
DISPLAY INVISIBLE (-100 1450);
FORCEPROP 0 LAST CDS_SEC 1
J 0
(-100 1450);
DISPLAY 1.021277 (-100 1450);
DISPLAY INVISIBLE (-100 1450);
FORCEADD GND..1
(725 -2625);
FORCEPROP 3 LASTPIN (725 -2575) SIG_NAME GND\g
J 0
(735 -2565);
DISPLAY 0.659574 (735 -2565);
PAINT MONO (735 -2565);
DISPLAY INVISIBLE (735 -2565);
FORCEPROP 1 LAST SIZE 1B
J 0
(800 -2675);
DISPLAY 0.872340 (800 -2675);
PAINT GREEN (800 -2675);
DISPLAY INVISIBLE (800 -2675);
FORCEPROP 2 LAST CDS_LIB logical_power
J 0
(725 -2625);
DISPLAY INVISIBLE (725 -2625);
FORCEPROP 1 LAST HDL_POWER GND
J 0
(725 -2475);
DISPLAY 0.872340 (725 -2475);
PAINT GREEN (725 -2475);
DISPLAY INVISIBLE (725 -2475);
FORCEPROP 1 LAST PATH I33
J 0
(800 -2625);
DISPLAY 0.872340 (800 -2625);
PAINT AQUA (800 -2625);
DISPLAY INVISIBLE (800 -2625);
FORCEADD Q_RES..2
(725 -2325);
FORCEPROP 1 LAST PART_NUMBER CS22492FB05
J 0
(775 -2400);
DISPLAY 0.510638 (775 -2400);
DISPLAY INVISIBLE (775 -2400);
FORCEPROP 1 LAST PACK_TYPE 0402LF
J 0
(775 -2425);
DISPLAY 0.510638 (775 -2425);
FORCEPROP 1 LAST TOLERANCE 1%
J 0
(775 -2325);
DISPLAY 0.510638 (775 -2325);
FORCEPROP 1 LAST MATERIAL CHIP
J 0
(775 -2375);
DISPLAY 0.510638 (775 -2375);
FORCEPROP 1 LAST WATTAGE 1/16W
J 0
(775 -2350);
DISPLAY 0.510638 (775 -2350);
FORCEPROP 1 LAST VALUE 2.49K
J 0
(775 -2300);
DISPLAY 0.510638 (775 -2300);
FORCEPROP 2 LAST ROOM E1S1_P3V3_BOM1
J 0
(775 -2225);
DISPLAY 0.404255 (775 -2225);
FORCEPROP 1 LAST LOCATION PR3969
J 0
(775 -2275);
DISPLAY 0.638298 (775 -2275);
FORCEPROP 1 LASTPIN (725 -2225) $PN 1
J 0
(730 -2263);
DISPLAY 0.787234 (730 -2263);
PAINT MONO (730 -2263);
FORCEPROP 1 LASTPIN (725 -2425) $PN 2
J 0
(730 -2415);
DISPLAY 0.787234 (730 -2415);
PAINT MONO (730 -2415);
FORCEPROP 2 LAST CDS_LIB pure_quanta
J 0
(725 -2325);
DISPLAY INVISIBLE (725 -2325);
FORCEPROP 1 LAST PATH I34
J 0
(775 -2150);
DISPLAY 0.978723 (775 -2150);
PAINT WHITE (775 -2150);
DISPLAY INVISIBLE (775 -2150);
FORCEPROP 0 LAST $SEC 1
J 0
(775 -2175);
DISPLAY 0.680851 (775 -2175);
PAINT MONO (775 -2175);
DISPLAY INVISIBLE (775 -2175);
FORCEPROP 0 LAST CDS_SEC 1
J 0
(775 -2200);
DISPLAY INVISIBLE (775 -2200);
FORCEADD MAX15090BEWIT..1
(1475 -1825);
FORCEPROP 1 LAST PART_NUMBER AL015080B00
J 0
(1222 -1181);
DISPLAY 0.723404 (1222 -1181);
PAINT GREEN (1222 -1181);
DISPLAY INVISIBLE (1222 -1181);
FORCEPROP 2 LAST ROOM E1S1_P3V3_BOM1
J 0
(1225 -950);
DISPLAY 1.021277 (1225 -950);
FORCEPROP 2 LAST VALUE MAX15090BEWI+T
J 0
(1225 -1050);
DISPLAY 1.021277 (1225 -1050);
FORCEPROP 2 LAST PART_TYPE SMLF
J 0
(1225 -1000);
DISPLAY 1.021277 (1225 -1000);
FORCEPROP 1 LAST MATERIAL IC
J 0
(1222 -1270);
DISPLAY 0.723404 (1222 -1270);
PAINT GREEN (1222 -1270);
FORCEPROP 1 LAST LOCATION PU295
J 0
(1222 -1097);
DISPLAY 0.723404 (1222 -1097);
PAINT GREEN (1222 -1097);
FORCEPROP 0 LASTPIN (1075 -2125) $PN B1
J 2
(1065 -2115);
DISPLAY 0.680851 (1065 -2115);
PAINT MONO (1065 -2115);
FORCEPROP 0 LASTPIN (1875 -2125) $PN A7
J 0
(1885 -2115);
DISPLAY 0.680851 (1885 -2115);
PAINT MONO (1885 -2115);
FORCEPROP 0 LASTPIN (1075 -2225) $PN B7
J 2
(1065 -2215);
DISPLAY 0.680851 (1065 -2215);
PAINT MONO (1065 -2215);
FORCEPROP 0 LASTPIN (1875 -1925) $PN C7
J 0
(1885 -1915);
DISPLAY 0.680851 (1885 -1915);
PAINT MONO (1885 -1915);
FORCEPROP 0 LASTPIN (1875 -1725) $PN A6
J 0
(1885 -1715);
DISPLAY 0.680851 (1885 -1715);
PAINT MONO (1885 -1715);
FORCEPROP 0 LASTPIN (1875 -2225) $PN B2
J 0
(1885 -2215);
DISPLAY 0.680851 (1885 -2215);
PAINT MONO (1885 -2215);
FORCEPROP 0 LASTPIN (1875 -2275) $PN C1
J 0
(1885 -2265);
DISPLAY 0.680851 (1885 -2265);
PAINT MONO (1885 -2265);
FORCEPROP 0 LASTPIN (1875 -2325) $PN C2
J 0
(1885 -2315);
DISPLAY 0.680851 (1885 -2315);
PAINT MONO (1885 -2315);
FORCEPROP 0 LASTPIN (1075 -1325) $PN A3
J 2
(1065 -1315);
DISPLAY 0.680851 (1065 -1315);
PAINT MONO (1065 -1315);
FORCEPROP 0 LASTPIN (1075 -1375) $PN A5
J 2
(1065 -1365);
DISPLAY 0.680851 (1065 -1365);
PAINT MONO (1065 -1365);
FORCEPROP 0 LASTPIN (1075 -1425) $PN B3
J 2
(1065 -1415);
DISPLAY 0.680851 (1065 -1415);
PAINT MONO (1065 -1415);
FORCEPROP 0 LASTPIN (1075 -1475) $PN B5
J 2
(1065 -1465);
DISPLAY 0.680851 (1065 -1465);
PAINT MONO (1065 -1465);
FORCEPROP 0 LASTPIN (1075 -1525) $PN C3
J 2
(1065 -1515);
DISPLAY 0.680851 (1065 -1515);
PAINT MONO (1065 -1515);
FORCEPROP 0 LASTPIN (1075 -1575) $PN C5
J 2
(1065 -1565);
DISPLAY 0.680851 (1065 -1565);
PAINT MONO (1065 -1565);
FORCEPROP 0 LASTPIN (1075 -1625) $PN D5
J 2
(1065 -1615);
DISPLAY 0.680851 (1065 -1615);
PAINT MONO (1065 -1615);
FORCEPROP 0 LASTPIN (1875 -2025) $PN A1
J 0
(1885 -2015);
DISPLAY 0.680851 (1885 -2015);
PAINT MONO (1885 -2015);
FORCEPROP 0 LASTPIN (1875 -1325) $PN A4
J 0
(1885 -1315);
DISPLAY 0.680851 (1885 -1315);
PAINT MONO (1885 -1315);
FORCEPROP 0 LASTPIN (1875 -1375) $PN B4
J 0
(1885 -1365);
DISPLAY 0.680851 (1885 -1365);
PAINT MONO (1885 -1365);
FORCEPROP 0 LASTPIN (1875 -1425) $PN B6
J 0
(1885 -1415);
DISPLAY 0.680851 (1885 -1415);
PAINT MONO (1885 -1415);
FORCEPROP 0 LASTPIN (1875 -1475) $PN C4
J 0
(1885 -1465);
DISPLAY 0.680851 (1885 -1465);
PAINT MONO (1885 -1465);
FORCEPROP 0 LASTPIN (1875 -1525) $PN C6
J 0
(1885 -1515);
DISPLAY 0.680851 (1885 -1515);
PAINT MONO (1885 -1515);
FORCEPROP 0 LASTPIN (1875 -1575) $PN D4
J 0
(1885 -1565);
DISPLAY 0.680851 (1885 -1565);
PAINT MONO (1885 -1565);
FORCEPROP 0 LASTPIN (1875 -1625) $PN D6
J 0
(1885 -1615);
DISPLAY 0.680851 (1885 -1615);
PAINT MONO (1885 -1615);
FORCEPROP 0 LASTPIN (1075 -2025) $PN D3
J 2
(1065 -2015);
DISPLAY 0.680851 (1065 -2015);
PAINT MONO (1065 -2015);
FORCEPROP 0 LASTPIN (1875 -1825) $PN D7
J 0
(1885 -1815);
DISPLAY 0.680851 (1885 -1815);
PAINT MONO (1885 -1815);
FORCEPROP 0 LASTPIN (1075 -1825) $PN D1
J 2
(1065 -1815);
DISPLAY 0.680851 (1065 -1815);
PAINT MONO (1065 -1815);
FORCEPROP 0 LASTPIN (1075 -1925) $PN D2
J 2
(1065 -1915);
DISPLAY 0.680851 (1065 -1915);
PAINT MONO (1065 -1915);
FORCEPROP 0 LASTPIN (1075 -1725) $PN A2
J 2
(1065 -1715);
DISPLAY 0.680851 (1065 -1715);
PAINT MONO (1065 -1715);
FORCEPROP 1 LAST PIN_NAMES_ROTATE TRUE
J 0
(1475 -1825);
DISPLAY 0.489362 (1475 -1825);
PAINT GREEN (1475 -1825);
DISPLAY INVISIBLE (1475 -1825);
FORCEPROP 2 LAST CDS_LIB pure_quanta
J 0
(1475 -1825);
DISPLAY INVISIBLE (1475 -1825);
FORCEPROP 1 LAST CDS_LMAN_SYM_OUTLINE -250,550,250,-550
J 0
(1475 -1825);
DISPLAY 0.468085 (1475 -1825);
PAINT GREEN (1475 -1825);
DISPLAY INVISIBLE (1475 -1825);
FORCEPROP 1 LAST PATH I35
J 0
(1725 -2375);
DISPLAY 0.723404 (1725 -2375);
PAINT GREEN (1725 -2375);
DISPLAY INVISIBLE (1725 -2375);
FORCEPROP 0 LAST $SEC 1
J 0
(1225 -950);
DISPLAY 0.680851 (1225 -950);
PAINT MONO (1225 -950);
DISPLAY INVISIBLE (1225 -950);
FORCEPROP 0 LAST CDS_SEC 1
J 0
(1225 -950);
DISPLAY 1.021277 (1225 -950);
DISPLAY INVISIBLE (1225 -950);
FORCEADD GND..1
(200 -1900);
FORCEPROP 3 LASTPIN (200 -1850) SIG_NAME GND\g
J 0
(210 -1840);
DISPLAY 0.659574 (210 -1840);
PAINT MONO (210 -1840);
DISPLAY INVISIBLE (210 -1840);
FORCEPROP 1 LAST SIZE 1B
J 0
(275 -1950);
DISPLAY 0.872340 (275 -1950);
PAINT GREEN (275 -1950);
DISPLAY INVISIBLE (275 -1950);
FORCEPROP 2 LAST CDS_LIB logical_power
J 0
(200 -1900);
DISPLAY INVISIBLE (200 -1900);
FORCEPROP 1 LAST HDL_POWER GND
J 0
(200 -1750);
DISPLAY 0.872340 (200 -1750);
PAINT GREEN (200 -1750);
DISPLAY INVISIBLE (200 -1750);
FORCEPROP 1 LAST PATH I36
J 0
(275 -1900);
DISPLAY 0.872340 (275 -1900);
PAINT AQUA (275 -1900);
DISPLAY INVISIBLE (275 -1900);
FORCEADD Q_CAP..1
(200 -1525);
FORCEPROP 1 LAST PART_NUMBER CH5104KEB02
J 0
(250 -1625);
DISPLAY 0.510638 (250 -1625);
DISPLAY INVISIBLE (250 -1625);
FORCEPROP 1 LAST MATERIAL X6S
J 0
(250 -1550);
DISPLAY 0.510638 (250 -1550);
FORCEPROP 1 LAST VOLTAGE 25V
J 0
(250 -1575);
DISPLAY 0.510638 (250 -1575);
FORCEPROP 1 LAST PACK_TYPE C0402
J 0
(250 -1600);
DISPLAY 0.510638 (250 -1600);
FORCEPROP 1 LAST VALUE 1UF
J 0
(250 -1525);
DISPLAY 0.510638 (250 -1525);
FORCEPROP 2 LAST ROOM E1S1_P3V3_BOM1
J 0
(250 -1450);
DISPLAY 0.404255 (250 -1450);
FORCEPROP 1 LAST LOCATION PC2210
J 0
(250 -1500);
DISPLAY 0.638298 (250 -1500);
FORCEPROP 1 LASTPIN (200 -1425) $PN 1
J 0
(210 -1445);
DISPLAY 0.787234 (210 -1445);
PAINT MONO (210 -1445);
FORCEPROP 1 LASTPIN (200 -1625) $PN 2
J 0
(210 -1645);
DISPLAY 0.787234 (210 -1645);
PAINT MONO (210 -1645);
FORCEPROP 1 LAST TOLERANCE 10%
J 0
(250 -1575);
DISPLAY 0.638298 (250 -1575);
DISPLAY INVISIBLE (250 -1575);
FORCEPROP 2 LAST CDS_LIB pure_quanta
J 0
(200 -1525);
DISPLAY INVISIBLE (200 -1525);
FORCEPROP 1 LAST PATH I37
J 0
(250 -1375);
DISPLAY 0.978723 (250 -1375);
PAINT WHITE (250 -1375);
DISPLAY INVISIBLE (250 -1375);
FORCEPROP 0 LAST $SEC 1
J 0
(250 -1450);
DISPLAY 0.680851 (250 -1450);
PAINT MONO (250 -1450);
DISPLAY INVISIBLE (250 -1450);
FORCEPROP 0 LAST CDS_SEC 1
J 0
(250 -1450);
DISPLAY 1.021277 (250 -1450);
DISPLAY INVISIBLE (250 -1450);
FORCEADD Q_CAP..1
R 1
(425 -1825);
FORCEPROP 1 LAST PART_NUMBER CH5104KEB02
J 0
(475 -1875);
DISPLAY 0.510638 (475 -1875);
DISPLAY INVISIBLE (475 -1875);
FORCEPROP 1 LAST PACK_TYPE C0402
J 0
(250 -1875);
DISPLAY 0.510638 (250 -1875);
FORCEPROP 1 LAST VOLTAGE 25V
J 0
(550 -1775);
DISPLAY 0.510638 (550 -1775);
FORCEPROP 1 LAST VALUE 1UF
J 0
(400 -1775);
DISPLAY 0.510638 (400 -1775);
FORCEPROP 2 LAST ROOM E1S1_P3V3_BOM1
J 0
(250 -1725);
DISPLAY 0.404255 (250 -1725);
FORCEPROP 1 LAST LOCATION PC2212
J 0
(250 -1775);
DISPLAY 0.638298 (250 -1775);
FORCEPROP 1 LASTPIN (325 -1825) $PN 1
R 1
J 0
(345 -1815);
DISPLAY 0.787234 (345 -1815);
PAINT MONO (345 -1815);
FORCEPROP 1 LASTPIN (525 -1825) $PN 2
R 1
J 0
(545 -1815);
DISPLAY 0.787234 (545 -1815);
PAINT MONO (545 -1815);
FORCEPROP 1 LAST TOLERANCE 10%
R 1
J 0
(475 -1775);
DISPLAY 0.638298 (475 -1775);
DISPLAY INVISIBLE (475 -1775);
FORCEPROP 1 LAST MATERIAL X6S
R 1
J 0
(425 -1775);
DISPLAY 0.638298 (425 -1775);
DISPLAY INVISIBLE (425 -1775);
FORCEPROP 2 LAST CDS_LIB pure_quanta
J 0
(425 -1825);
DISPLAY INVISIBLE (425 -1825);
FORCEPROP 1 LAST PATH I38
R 1
J 0
(275 -1775);
DISPLAY 0.978723 (275 -1775);
PAINT WHITE (275 -1775);
DISPLAY INVISIBLE (275 -1775);
FORCEPROP 0 LAST $SEC 1
R 1
J 0
(250 -1725);
DISPLAY 0.680851 (250 -1725);
PAINT MONO (250 -1725);
DISPLAY INVISIBLE (250 -1725);
FORCEPROP 0 LAST CDS_SEC 1
R 1
J 0
(250 -1725);
DISPLAY 1.021277 (250 -1725);
DISPLAY INVISIBLE (250 -1725);
FORCEADD Q_RES..2
(200 -1100);
FORCEPROP 1 LAST PART_NUMBER CS01002FB07
J 0
(250 -1150);
DISPLAY 0.404255 (250 -1150);
DISPLAY INVISIBLE (250 -1150);
FORCEPROP 1 LAST TOLERANCE 1%
J 0
(250 -1075);
DISPLAY 0.404255 (250 -1075);
FORCEPROP 1 LAST WATTAGE 1/16W
J 0
(250 -1100);
DISPLAY 0.404255 (250 -1100);
FORCEPROP 1 LAST MATERIAL CHIP
J 0
(250 -1125);
DISPLAY 0.404255 (250 -1125);
FORCEPROP 1 LAST PACK_TYPE 0402LF
J 0
(250 -1175);
DISPLAY 0.404255 (250 -1175);
FORCEPROP 1 LAST VALUE 10
J 0
(250 -1050);
DISPLAY 0.404255 (250 -1050);
FORCEPROP 2 LAST ROOM E1S1_P3V3_BOM1
J 0
(250 -975);
DISPLAY 0.510638 (250 -975);
FORCEPROP 1 LAST LOCATION PR3967
J 0
(250 -1025);
DISPLAY 0.638298 (250 -1025);
FORCEPROP 1 LASTPIN (200 -1000) $PN 1
J 0
(205 -1038);
DISPLAY 0.787234 (205 -1038);
PAINT MONO (205 -1038);
FORCEPROP 1 LASTPIN (200 -1200) $PN 2
J 0
(205 -1190);
DISPLAY 0.787234 (205 -1190);
PAINT MONO (205 -1190);
FORCEPROP 2 LAST CDS_LIB pure_quanta
J 0
(200 -1100);
DISPLAY INVISIBLE (200 -1100);
FORCEPROP 1 LAST PATH I39
J 0
(250 -925);
DISPLAY 0.978723 (250 -925);
PAINT WHITE (250 -925);
DISPLAY INVISIBLE (250 -925);
FORCEPROP 0 LAST $SEC 1
J 0
(250 -975);
DISPLAY 0.680851 (250 -975);
PAINT MONO (250 -975);
DISPLAY INVISIBLE (250 -975);
FORCEPROP 0 LAST CDS_SEC 1
J 0
(250 -975);
DISPLAY 1.021277 (250 -975);
DISPLAY INVISIBLE (250 -975);
FORCEADD MOSFET_NCH_DUAL..2
(-2525 -2050);
FORCEPROP 1 LAST PART_NUMBER BAM138K0003
J 0
(-2374 -2144);
DISPLAY 0.723404 (-2374 -2144);
PAINT GREEN (-2374 -2144);
DISPLAY INVISIBLE (-2374 -2144);
FORCEPROP 1 LAST MATERIAL IC
J 0
(-2374 -2199);
DISPLAY 0.723404 (-2374 -2199);
PAINT GREEN (-2374 -2199);
FORCEPROP 2 LAST ROOM E1S1_P3V3_BOM1
J 0
(-2350 -1925);
DISPLAY 0.808511 (-2350 -1925);
FORCEPROP 2 LAST PART_TYPE SMLF
J 0
(-2350 -1975);
DISPLAY 1.021277 (-2350 -1975);
FORCEPROP 2 LAST VALUE PJT138K
J 0
(-2350 -2025);
DISPLAY 1.021277 (-2350 -2025);
FORCEPROP 1 LAST $LOCATION Q126
J 0
(-2374 -2074);
DISPLAY 0.723404 (-2374 -2074);
PAINT GREEN (-2374 -2074);
FORCEPROP 0 LASTPIN (-2475 -1850) $PN 3
R 1
J 0
(-2485 -1840);
DISPLAY 0.680851 (-2485 -1840);
PAINT MONO (-2485 -1840);
FORCEPROP 0 LASTPIN (-2725 -2100) $PN 5
J 2
(-2735 -2090);
DISPLAY 0.680851 (-2735 -2090);
PAINT MONO (-2735 -2090);
FORCEPROP 0 LASTPIN (-2475 -2250) $PN 4
R 1
J 2
(-2485 -2260);
DISPLAY 0.680851 (-2485 -2260);
PAINT MONO (-2485 -2260);
FORCEPROP 2 LAST CDS_LIB pure_quanta
J 0
(-2525 -2050);
DISPLAY INVISIBLE (-2525 -2050);
FORCEPROP 1 LAST CDS_LMAN_SYM_OUTLINE -150,150,150,-150
J 0
(-2525 -2050);
DISPLAY 0.468085 (-2525 -2050);
PAINT GREEN (-2525 -2050);
DISPLAY INVISIBLE (-2525 -2050);
FORCEPROP 1 LAST NEEDS_NO_SIZE TRUE
J 0
(-2375 -2159);
DISPLAY 0.468085 (-2375 -2159);
PAINT GREEN (-2375 -2159);
DISPLAY INVISIBLE (-2375 -2159);
FORCEPROP 1 LAST PATH I4
J 0
(-2375 -2200);
DISPLAY 0.723404 (-2375 -2200);
PAINT GREEN (-2375 -2200);
DISPLAY INVISIBLE (-2375 -2200);
FORCEPROP 0 LAST CDS_LOCATION Q126
J 0
(-2350 -1925);
DISPLAY 1.021277 (-2350 -1925);
DISPLAY INVISIBLE (-2350 -1925);
FORCEPROP 0 LAST $SEC 2
J 0
(-2350 -1925);
DISPLAY 0.680851 (-2350 -1925);
PAINT MONO (-2350 -1925);
DISPLAY INVISIBLE (-2350 -1925);
FORCEPROP 0 LAST CDS_SEC 2
J 0
(-2350 -1925);
DISPLAY 1.021277 (-2350 -1925);
DISPLAY INVISIBLE (-2350 -1925);
FORCEADD GND..1
(2200 -2500);
FORCEPROP 3 LASTPIN (2200 -2450) SIG_NAME GND\g
J 0
(2210 -2440);
DISPLAY 0.659574 (2210 -2440);
PAINT MONO (2210 -2440);
DISPLAY INVISIBLE (2210 -2440);
FORCEPROP 2 LAST CDS_LIB logical_power
J 0
(2200 -2500);
DISPLAY INVISIBLE (2200 -2500);
FORCEPROP 1 LAST HDL_POWER GND
J 0
(2200 -2350);
DISPLAY 0.872340 (2200 -2350);
PAINT GREEN (2200 -2350);
DISPLAY INVISIBLE (2200 -2350);
FORCEPROP 1 LAST SIZE 1B
J 0
(2275 -2550);
DISPLAY 0.872340 (2275 -2550);
PAINT GREEN (2275 -2550);
DISPLAY INVISIBLE (2275 -2550);
FORCEPROP 1 LAST PATH I40
J 0
(2275 -2500);
DISPLAY 0.872340 (2275 -2500);
PAINT AQUA (2275 -2500);
DISPLAY INVISIBLE (2275 -2500);
FORCEADD Q_RES..2
(2325 -2175);
FORCEPROP 1 LAST PART_NUMBER CS29762FB05
J 0
(2375 -2275);
DISPLAY 0.404255 (2375 -2275);
DISPLAY INVISIBLE (2375 -2275);
FORCEPROP 1 LAST PACK_TYPE 0402LF
J 0
(2375 -2300);
DISPLAY 0.404255 (2375 -2300);
FORCEPROP 1 LAST MATERIAL CHIP
J 0
(2375 -2250);
DISPLAY 0.404255 (2375 -2250);
FORCEPROP 1 LAST VALUE 9.76K
J 0
(2375 -2175);
DISPLAY 0.404255 (2375 -2175);
FORCEPROP 1 LAST TOLERANCE 1%
J 0
(2375 -2200);
DISPLAY 0.404255 (2375 -2200);
FORCEPROP 1 LAST WATTAGE 1/16W
J 0
(2375 -2225);
DISPLAY 0.404255 (2375 -2225);
FORCEPROP 2 LAST ROOM E1S1_P3V3_BOM1
J 0
(2375 -2100);
DISPLAY 0.510638 (2375 -2100);
FORCEPROP 1 LAST LOCATION PR3971
J 0
(2375 -2150);
DISPLAY 0.638298 (2375 -2150);
FORCEPROP 1 LASTPIN (2325 -2075) $PN 1
J 0
(2330 -2113);
DISPLAY 0.787234 (2330 -2113);
PAINT MONO (2330 -2113);
FORCEPROP 1 LASTPIN (2325 -2275) $PN 2
J 0
(2330 -2265);
DISPLAY 0.787234 (2330 -2265);
PAINT MONO (2330 -2265);
FORCEPROP 2 LAST CDS_LIB pure_quanta
J 0
(2325 -2175);
DISPLAY INVISIBLE (2325 -2175);
FORCEPROP 1 LAST PATH I41
J 0
(2375 -2000);
DISPLAY 0.978723 (2375 -2000);
PAINT WHITE (2375 -2000);
DISPLAY INVISIBLE (2375 -2000);
FORCEPROP 0 LAST $SEC 1
J 0
(2375 -2000);
DISPLAY 0.680851 (2375 -2000);
PAINT MONO (2375 -2000);
DISPLAY INVISIBLE (2375 -2000);
FORCEPROP 0 LAST CDS_SEC 1
J 0
(2375 -2000);
DISPLAY 1.021277 (2375 -2000);
DISPLAY INVISIBLE (2375 -2000);
FORCEADD Q_CAP..1
(2275 -1500);
FORCEPROP 1 LAST PART_NUMBER CH31006KB18
J 0
(2325 -1575);
DISPLAY 0.404255 (2325 -1575);
DISPLAY INVISIBLE (2325 -1575);
FORCEPROP 1 LAST VALUE 0.01UF
J 0
(2320 -1417);
DISPLAY 0.404255 (2320 -1417);
FORCEPROP 1 LAST VOLTAGE 50V
J 0
(2325 -1475);
DISPLAY 0.404255 (2325 -1475);
FORCEPROP 1 LAST MATERIAL EMPTY
J 0
(2325 -1625);
DISPLAY 0.638298 (2325 -1625);
PAINT RED (2325 -1625);
FORCEPROP 1 LAST PACK_TYPE C0402
J 0
(2325 -1525);
DISPLAY 0.404255 (2325 -1525);
FORCEPROP 1 LAST LOCATION PC2213
J 0
(2320 -1367);
DISPLAY 0.510638 (2320 -1367);
FORCEPROP 1 LASTPIN (2275 -1400) $PN 1
J 0
(2285 -1420);
DISPLAY 0.787234 (2285 -1420);
PAINT MONO (2285 -1420);
FORCEPROP 1 LASTPIN (2275 -1600) $PN 2
J 0
(2285 -1620);
DISPLAY 0.787234 (2285 -1620);
PAINT MONO (2285 -1620);
FORCEPROP 1 LAST TOLERANCE 10%
J 0
(2325 -1550);
DISPLAY 0.638298 (2325 -1550);
DISPLAY INVISIBLE (2325 -1550);
FORCEPROP 2 LAST CDS_LIB pure_quanta
J 0
(2275 -1500);
DISPLAY INVISIBLE (2275 -1500);
FORCEPROP 1 LAST PATH I42
J 0
(2325 -1350);
DISPLAY 0.978723 (2325 -1350);
PAINT WHITE (2325 -1350);
DISPLAY INVISIBLE (2325 -1350);
FORCEPROP 0 LAST $SEC 1
J 0
(2325 -1350);
DISPLAY 0.680851 (2325 -1350);
PAINT MONO (2325 -1350);
DISPLAY INVISIBLE (2325 -1350);
FORCEPROP 0 LAST CDS_SEC 1
J 0
(2325 -1350);
DISPLAY 1.021277 (2325 -1350);
DISPLAY INVISIBLE (2325 -1350);
FORCEADD Q_RES..2
(2550 -1500);
FORCEPROP 1 LAST PART_NUMBER CS61002FB02
J 0
(2590 -1625);
DISPLAY 0.510638 (2590 -1625);
DISPLAY INVISIBLE (2590 -1625);
FORCEPROP 1 LAST VALUE 10M
J 0
(2595 -1425);
DISPLAY 0.510638 (2595 -1425);
FORCEPROP 1 LAST TOLERANCE 1%
J 0
(2595 -1475);
DISPLAY 0.510638 (2595 -1475);
FORCEPROP 2 LAST ROOM E1S1_P3V3_BOM1
J 0
(2600 -1325);
DISPLAY 0.510638 (2600 -1325);
FORCEPROP 1 LAST MATERIAL CHIP
J 0
(2590 -1575);
DISPLAY 0.510638 (2590 -1575);
FORCEPROP 1 LAST PACK_TYPE 0402LF
J 0
(2590 -1675);
DISPLAY 0.510638 (2590 -1675);
FORCEPROP 1 LAST WATTAGE 1/16W
J 0
(2590 -1525);
DISPLAY 0.510638 (2590 -1525);
FORCEPROP 1 LAST LOCATION PR4527
J 0
(2595 -1375);
DISPLAY 0.978723 (2595 -1375);
FORCEPROP 1 LASTPIN (2550 -1400) $PN 1
J 0
(2555 -1438);
DISPLAY 0.787234 (2555 -1438);
PAINT MONO (2555 -1438);
FORCEPROP 1 LASTPIN (2550 -1600) $PN 2
J 0
(2555 -1590);
DISPLAY 0.787234 (2555 -1590);
PAINT MONO (2555 -1590);
FORCEPROP 2 LAST CDS_LIB pure_quanta
J 0
(2550 -1500);
DISPLAY INVISIBLE (2550 -1500);
FORCEPROP 1 LAST PATH I43
J 0
(2600 -1325);
DISPLAY 0.978723 (2600 -1325);
PAINT WHITE (2600 -1325);
DISPLAY INVISIBLE (2600 -1325);
FORCEPROP 0 LAST $SEC 1
J 0
(2600 -1325);
DISPLAY 0.680851 (2600 -1325);
PAINT MONO (2600 -1325);
DISPLAY INVISIBLE (2600 -1325);
FORCEPROP 0 LAST CDS_SEC 1
J 0
(2600 -1325);
DISPLAY 1.021277 (2600 -1325);
DISPLAY INVISIBLE (2600 -1325);
FORCEADD Q_RES..1
(2975 -1825);
FORCEPROP 1 LAST PART_NUMBER CS00002JB13
J 0
(2800 -1875);
DISPLAY 0.595745 (2800 -1875);
DISPLAY INVISIBLE (2800 -1875);
FORCEPROP 1 LAST VALUE 0
J 2
(3125 -1825);
DISPLAY 0.595745 (3125 -1825);
FORCEPROP 1 LAST TOLERANCE 5%
J 0
(3150 -1825);
DISPLAY 0.595745 (3150 -1825);
FORCEPROP 1 LAST PACK_TYPE 0402LF
J 0
(3125 -1875);
DISPLAY 0.595745 (3125 -1875);
FORCEPROP 1 LAST WATTAGE 1/16W
J 2
(2775 -1875);
DISPLAY 0.595745 (2775 -1875);
FORCEPROP 1 LAST MATERIAL CHIP
J 0
(2750 -1825);
DISPLAY 0.595745 (2750 -1825);
FORCEPROP 2 LAST ROOM E1S1_P3V3_BOM1
J 0
(2800 -1900);
DISPLAY 0.510638 (2800 -1900);
FORCEPROP 1 LAST $LOCATION R3973
J 0
(2575 -1825);
DISPLAY 0.638298 (2575 -1825);
FORCEPROP 1 LASTPIN (2875 -1825) $PN 1
J 0
(2887 -1813);
DISPLAY 0.787234 (2887 -1813);
PAINT MONO (2887 -1813);
FORCEPROP 1 LASTPIN (3075 -1825) $PN 2
J 0
(3037 -1813);
DISPLAY 0.787234 (3037 -1813);
PAINT MONO (3037 -1813);
FORCEPROP 2 LAST CDS_LIB pure_quanta
J 0
(2975 -1825);
DISPLAY INVISIBLE (2975 -1825);
FORCEPROP 1 LAST PATH I44
J 0
(2925 -1675);
DISPLAY 0.978723 (2925 -1675);
PAINT WHITE (2925 -1675);
DISPLAY INVISIBLE (2925 -1675);
FORCEPROP 0 LAST CDS_LOCATION R3973
J 0
(3150 -1775);
DISPLAY 1.021277 (3150 -1775);
DISPLAY INVISIBLE (3150 -1775);
FORCEPROP 0 LAST $SEC 1
J 0
(2925 -1750);
DISPLAY 0.680851 (2925 -1750);
PAINT MONO (2925 -1750);
DISPLAY INVISIBLE (2925 -1750);
FORCEPROP 0 LAST CDS_SEC 1
J 0
(2925 -1750);
DISPLAY 1.021277 (2925 -1750);
DISPLAY INVISIBLE (2925 -1750);
FORCEADD Q_CAP..1
R 1
(3025 -1725);
FORCEPROP 1 LAST PART_NUMBER CH2686K1B01
J 0
(3050 -1675);
DISPLAY 0.404255 (3050 -1675);
DISPLAY INVISIBLE (3050 -1675);
FORCEPROP 1 LAST VALUE 6800PF
J 0
(2925 -1650);
DISPLAY 0.638298 (2925 -1650);
FORCEPROP 1 LAST PACK_TYPE C0402
J 0
(2800 -1775);
DISPLAY 0.638298 (2800 -1775);
FORCEPROP 2 LAST ROOM E1S1_P3V3_BOM1
J 0
(2975 -1600);
DISPLAY 0.510638 (2975 -1600);
FORCEPROP 1 LAST VOLTAGE 50V
J 0
(3125 -1650);
DISPLAY 0.638298 (3125 -1650);
FORCEPROP 1 LAST LOCATION PC2216
J 0
(2750 -1725);
DISPLAY 0.638298 (2750 -1725);
FORCEPROP 1 LASTPIN (2925 -1725) $PN 1
R 1
J 0
(2945 -1715);
DISPLAY 0.787234 (2945 -1715);
PAINT MONO (2945 -1715);
FORCEPROP 1 LASTPIN (3125 -1725) $PN 2
R 1
J 0
(3145 -1715);
DISPLAY 0.787234 (3145 -1715);
PAINT MONO (3145 -1715);
FORCEPROP 1 LAST TOLERANCE 10%
R 1
J 0
(3075 -1675);
DISPLAY 0.638298 (3075 -1675);
DISPLAY INVISIBLE (3075 -1675);
FORCEPROP 1 LAST MATERIAL X7R
R 1
J 0
(3025 -1675);
DISPLAY 0.638298 (3025 -1675);
DISPLAY INVISIBLE (3025 -1675);
FORCEPROP 2 LAST CDS_LIB pure_quanta
R 1
J 0
(3025 -1725);
DISPLAY INVISIBLE (3025 -1725);
FORCEPROP 1 LAST PATH I45
R 1
J 0
(2875 -1675);
DISPLAY 0.978723 (2875 -1675);
PAINT WHITE (2875 -1675);
DISPLAY INVISIBLE (2875 -1675);
FORCEPROP 0 LAST $SEC 1
R 1
J 0
(3125 -1600);
DISPLAY 0.680851 (3125 -1600);
PAINT MONO (3125 -1600);
DISPLAY INVISIBLE (3125 -1600);
FORCEPROP 0 LAST CDS_SEC 1
R 1
J 0
(3125 -1600);
DISPLAY 1.021277 (3125 -1600);
DISPLAY INVISIBLE (3125 -1600);
FORCEADD SCHOTTKY_AC..1
R 1
(2700 -875);
FORCEPROP 1 LAST PART_NUMBER BC000340Z30
J 0
(2750 -950);
DISPLAY 0.595745 (2750 -950);
PAINT GREEN (2750 -950);
DISPLAY INVISIBLE (2750 -950);
FORCEPROP 2 LAST VALUE B340A-13-F
J 0
(2750 -900);
DISPLAY 0.638298 (2750 -900);
FORCEPROP 1 LAST MATERIAL IC
J 0
(2750 -975);
DISPLAY 0.723404 (2750 -975);
PAINT GREEN (2750 -975);
FORCEPROP 1 LAST LOCATION PD113
J 0
(2750 -850);
DISPLAY 0.723404 (2750 -850);
PAINT GREEN (2750 -850);
FORCEPROP 0 LASTPIN (2700 -1000) $PN A
R 1
J 2
(2690 -965);
DISPLAY 0.808511 (2690 -965);
FORCEPROP 0 LASTPIN (2700 -750) $PN C
R 1
J 0
(2690 -790);
DISPLAY 0.808511 (2690 -790);
FORCEPROP 0 LAST PART_TYPE SMLF
J 0
(2750 -700);
DISPLAY 1.021277 (2750 -700);
DISPLAY INVISIBLE (2750 -700);
FORCEPROP 1 LAST CDS_LMAN_SYM_OUTLINE -75,50,75,-50
R 1
J 0
(2700 -875);
DISPLAY 0.468085 (2700 -875);
PAINT GREEN (2700 -875);
DISPLAY INVISIBLE (2700 -875);
FORCEPROP 2 LAST CDS_LIB pure_quanta
R 1
J 0
(2700 -875);
DISPLAY INVISIBLE (2700 -875);
FORCEPROP 1 LAST NEEDS_NO_SIZE TRUE
R 1
J 0
(2750 -800);
DISPLAY 0.468085 (2750 -800);
PAINT GREEN (2750 -800);
DISPLAY INVISIBLE (2750 -800);
FORCEPROP 1 LAST PATH I46
R 1
J 0
(2700 -875);
DISPLAY 0.723404 (2700 -875);
PAINT GREEN (2700 -875);
DISPLAY INVISIBLE (2700 -875);
FORCEPROP 0 LAST $SEC 1
R 1
J 0
(2750 -800);
DISPLAY INVISIBLE (2750 -800);
FORCEPROP 0 LAST CDS_SEC 1
R 1
J 0
(2750 -800);
DISPLAY INVISIBLE (2750 -800);
FORCEADD GND..1
(3150 -1775);
FORCEPROP 3 LASTPIN (3150 -1725) SIG_NAME GND\g
J 0
(3160 -1715);
DISPLAY 0.659574 (3160 -1715);
PAINT MONO (3160 -1715);
DISPLAY INVISIBLE (3160 -1715);
FORCEPROP 1 LAST HDL_POWER GND
J 0
(3150 -1625);
DISPLAY 0.872340 (3150 -1625);
PAINT GREEN (3150 -1625);
DISPLAY INVISIBLE (3150 -1625);
FORCEPROP 2 LAST CDS_LIB logical_power
J 0
(3150 -1775);
DISPLAY INVISIBLE (3150 -1775);
FORCEPROP 1 LAST SIZE 1B
J 0
(3225 -1825);
DISPLAY 0.872340 (3225 -1825);
PAINT GREEN (3225 -1825);
DISPLAY INVISIBLE (3225 -1825);
FORCEPROP 1 LAST PATH I47
J 0
(3225 -1775);
DISPLAY 0.872340 (3225 -1775);
PAINT AQUA (3225 -1775);
DISPLAY INVISIBLE (3225 -1775);
FORCEADD Q_RES..2
(3325 -1525);
FORCEPROP 1 LAST PART_NUMBER CS41002FB09
J 0
(3365 -1650);
DISPLAY 0.510638 (3365 -1650);
DISPLAY INVISIBLE (3365 -1650);
FORCEPROP 1 LAST TOLERANCE 1%
J 0
(3370 -1500);
DISPLAY 0.510638 (3370 -1500);
FORCEPROP 1 LAST VALUE 100K
J 0
(3370 -1450);
DISPLAY 0.510638 (3370 -1450);
FORCEPROP 1 LAST WATTAGE 1/16W
J 0
(3365 -1550);
DISPLAY 0.510638 (3365 -1550);
FORCEPROP 2 LAST ROOM E1S1_P3V3_BOM1
J 0
(3375 -1350);
DISPLAY 0.510638 (3375 -1350);
FORCEPROP 1 LAST MATERIAL CHIP
J 0
(3365 -1600);
DISPLAY 0.510638 (3365 -1600);
FORCEPROP 1 LAST PACK_TYPE 0402LF
J 0
(3365 -1700);
DISPLAY 0.510638 (3365 -1700);
FORCEPROP 1 LAST LOCATION R3977
J 0
(3370 -1400);
DISPLAY 0.638298 (3370 -1400);
FORCEPROP 1 LASTPIN (3325 -1425) $PN 1
J 0
(3330 -1463);
DISPLAY 0.787234 (3330 -1463);
PAINT MONO (3330 -1463);
FORCEPROP 1 LASTPIN (3325 -1625) $PN 2
J 0
(3330 -1615);
DISPLAY 0.787234 (3330 -1615);
PAINT MONO (3330 -1615);
FORCEPROP 2 LAST CDS_LIB pure_quanta
J 0
(3325 -1525);
DISPLAY INVISIBLE (3325 -1525);
FORCEPROP 1 LAST PATH I48
J 0
(3375 -1350);
DISPLAY 0.978723 (3375 -1350);
PAINT WHITE (3375 -1350);
DISPLAY INVISIBLE (3375 -1350);
FORCEPROP 0 LAST $SEC 1
J 0
(3375 -1350);
DISPLAY 0.680851 (3375 -1350);
PAINT MONO (3375 -1350);
DISPLAY INVISIBLE (3375 -1350);
FORCEPROP 0 LAST CDS_SEC 1
J 0
(3375 -1350);
DISPLAY 1.021277 (3375 -1350);
DISPLAY INVISIBLE (3375 -1350);
FORCEADD VCCAUX15..1
(3525 -1200);
FORCEPROP 3 LASTPIN (3525 -1250) SIG_NAME P3V3_AUX\g
J 0
(3535 -1240);
DISPLAY 0.659574 (3535 -1240);
PAINT MONO (3535 -1240);
DISPLAY INVISIBLE (3535 -1240);
FORCEPROP 1 LAST HDL_POWER P3V3_AUX
J 1
(3525 -1150);
DISPLAY 0.723404 (3525 -1150);
PAINT GREEN (3525 -1150);
FORCEPROP 2 LAST CDS_LIB logical_power
J 0
(3525 -1200);
DISPLAY INVISIBLE (3525 -1200);
FORCEPROP 1 LAST PATH I49
J 0
(3575 -1175);
DISPLAY 0.872340 (3575 -1175);
PAINT AQUA (3575 -1175);
DISPLAY INVISIBLE (3575 -1175);
FORCEADD GND..1
(-2475 -2350);
FORCEPROP 3 LASTPIN (-2475 -2300) SIG_NAME GND\g
J 0
(-2465 -2290);
DISPLAY 0.659574 (-2465 -2290);
PAINT MONO (-2465 -2290);
DISPLAY INVISIBLE (-2465 -2290);
FORCEPROP 1 LAST SIZE 1B
J 0
(-2400 -2400);
DISPLAY 0.872340 (-2400 -2400);
PAINT GREEN (-2400 -2400);
DISPLAY INVISIBLE (-2400 -2400);
FORCEPROP 1 LAST HDL_POWER GND
J 0
(-2475 -2200);
DISPLAY 0.872340 (-2475 -2200);
PAINT GREEN (-2475 -2200);
DISPLAY INVISIBLE (-2475 -2200);
FORCEPROP 2 LAST CDS_LIB logical_power
J 0
(-2475 -2350);
DISPLAY INVISIBLE (-2475 -2350);
FORCEPROP 1 LAST PATH I5
J 0
(-2400 -2350);
DISPLAY 0.872340 (-2400 -2350);
PAINT AQUA (-2400 -2350);
DISPLAY INVISIBLE (-2400 -2350);
FORCEADD Q_RES..2
(3725 -1525);
FORCEPROP 1 LAST PART_NUMBER CS41002FB09
J 0
(3765 -1650);
DISPLAY 0.510638 (3765 -1650);
DISPLAY INVISIBLE (3765 -1650);
FORCEPROP 1 LAST VALUE 100K
J 0
(3770 -1450);
DISPLAY 0.510638 (3770 -1450);
FORCEPROP 1 LAST TOLERANCE 1%
J 0
(3770 -1500);
DISPLAY 0.510638 (3770 -1500);
FORCEPROP 1 LAST WATTAGE 1/16W
J 0
(3765 -1550);
DISPLAY 0.510638 (3765 -1550);
FORCEPROP 1 LAST MATERIAL CHIP
J 0
(3765 -1600);
DISPLAY 0.510638 (3765 -1600);
FORCEPROP 1 LAST PACK_TYPE 0402LF
J 0
(3765 -1700);
DISPLAY 0.510638 (3765 -1700);
FORCEPROP 2 LAST ROOM E1S1_P3V3_BOM1
J 0
(3775 -1350);
DISPLAY 0.510638 (3775 -1350);
FORCEPROP 1 LAST LOCATION R3979
J 0
(3770 -1400);
DISPLAY 0.638298 (3770 -1400);
FORCEPROP 1 LASTPIN (3725 -1425) $PN 1
J 0
(3730 -1463);
DISPLAY 0.787234 (3730 -1463);
PAINT MONO (3730 -1463);
FORCEPROP 1 LASTPIN (3725 -1625) $PN 2
J 0
(3730 -1615);
DISPLAY 0.787234 (3730 -1615);
PAINT MONO (3730 -1615);
FORCEPROP 2 LAST CDS_LIB pure_quanta
J 0
(3725 -1525);
DISPLAY INVISIBLE (3725 -1525);
FORCEPROP 1 LAST PATH I50
J 0
(3775 -1350);
DISPLAY 0.978723 (3775 -1350);
PAINT WHITE (3775 -1350);
DISPLAY INVISIBLE (3775 -1350);
FORCEPROP 0 LAST $SEC 1
J 0
(3775 -1350);
DISPLAY 0.680851 (3775 -1350);
PAINT MONO (3775 -1350);
DISPLAY INVISIBLE (3775 -1350);
FORCEPROP 0 LAST CDS_SEC 1
J 0
(3775 -1350);
DISPLAY 1.021277 (3775 -1350);
DISPLAY INVISIBLE (3775 -1350);
FORCEADD GND..1
(3775 -1200);
FORCEPROP 3 LASTPIN (3775 -1150) SIG_NAME GND\g
J 0
(3785 -1140);
DISPLAY 0.659574 (3785 -1140);
PAINT MONO (3785 -1140);
DISPLAY INVISIBLE (3785 -1140);
FORCEPROP 2 LAST CDS_LIB logical_power
J 0
(3775 -1200);
DISPLAY INVISIBLE (3775 -1200);
FORCEPROP 1 LAST HDL_POWER GND
J 0
(3775 -1050);
DISPLAY 0.872340 (3775 -1050);
PAINT GREEN (3775 -1050);
DISPLAY INVISIBLE (3775 -1050);
FORCEPROP 1 LAST SIZE 1B
J 0
(3850 -1250);
DISPLAY 0.872340 (3850 -1250);
PAINT GREEN (3850 -1250);
DISPLAY INVISIBLE (3850 -1250);
FORCEPROP 1 LAST PATH I51
J 0
(3850 -1200);
DISPLAY 0.872340 (3850 -1200);
PAINT AQUA (3850 -1200);
DISPLAY INVISIBLE (3850 -1200);
FORCEADD Q_CAP..1
(3200 -900);
FORCEPROP 1 LAST PART_NUMBER CH4104K1B00
J 0
(3250 -1050);
DISPLAY 0.638298 (3250 -1050);
DISPLAY INVISIBLE (3250 -1050);
FORCEPROP 1 LAST VALUE 0.1UF
J 0
(3250 -850);
DISPLAY 0.638298 (3250 -850);
FORCEPROP 1 LAST VOLTAGE 25V
J 0
(3250 -900);
DISPLAY 0.638298 (3250 -900);
FORCEPROP 1 LAST PACK_TYPE 0402
J 0
(3250 -1000);
DISPLAY 0.638298 (3250 -1000);
FORCEPROP 1 LAST MATERIAL X7R
J 0
(3250 -950);
DISPLAY 0.638298 (3250 -950);
FORCEPROP 1 LAST LOCATION PC2218
J 0
(3250 -800);
DISPLAY 0.638298 (3250 -800);
FORCEPROP 1 LASTPIN (3200 -800) $PN 1
J 0
(3210 -820);
DISPLAY 0.787234 (3210 -820);
PAINT MONO (3210 -820);
FORCEPROP 1 LASTPIN (3200 -1000) $PN 2
J 0
(3210 -1020);
DISPLAY 0.787234 (3210 -1020);
PAINT MONO (3210 -1020);
FORCEPROP 1 LAST TOLERANCE 10%
J 0
(3250 -950);
DISPLAY 0.978723 (3250 -950);
DISPLAY INVISIBLE (3250 -950);
FORCEPROP 2 LAST CDS_LIB pure_quanta
J 0
(3200 -900);
DISPLAY INVISIBLE (3200 -900);
FORCEPROP 1 LAST PATH I52
J 0
(3250 -750);
DISPLAY 0.978723 (3250 -750);
PAINT WHITE (3250 -750);
DISPLAY INVISIBLE (3250 -750);
FORCEPROP 0 LAST $SEC 1
J 0
(3250 -750);
DISPLAY 0.680851 (3250 -750);
PAINT MONO (3250 -750);
DISPLAY INVISIBLE (3250 -750);
FORCEPROP 0 LAST CDS_SEC 1
J 0
(3250 -750);
DISPLAY 1.021277 (3250 -750);
DISPLAY INVISIBLE (3250 -750);
FORCEADD Q_CAP..1
(3775 -900);
FORCEPROP 1 LAST PART_NUMBER CH6103KEA01
J 0
(3825 -1050);
DISPLAY 0.638298 (3825 -1050);
DISPLAY INVISIBLE (3825 -1050);
FORCEPROP 1 LAST VOLTAGE 16V
J 0
(3825 -900);
DISPLAY 0.638298 (3825 -900);
FORCEPROP 1 LAST VALUE 10UF
J 0
(3825 -850);
DISPLAY 0.638298 (3825 -850);
FORCEPROP 1 LAST PACK_TYPE C0805
J 0
(3825 -1000);
DISPLAY 0.638298 (3825 -1000);
FORCEPROP 1 LAST MATERIAL X6S
J 0
(3825 -950);
DISPLAY 0.638298 (3825 -950);
FORCEPROP 1 LAST LOCATION PC2220
J 0
(3825 -800);
DISPLAY 0.680851 (3825 -800);
FORCEPROP 2 LAST CDS_LIB pure_quanta
J 0
(3775 -900);
DISPLAY INVISIBLE (3775 -900);
FORCEPROP 1 LAST TOLERANCE 10%
J 0
(3564 -940);
DISPLAY 0.787234 (3564 -940);
PAINT GREEN (3564 -940);
DISPLAY INVISIBLE (3564 -940);
FORCEPROP 1 LAST PATH I53
J 0
(3825 -750);
DISPLAY 0.978723 (3825 -750);
PAINT WHITE (3825 -750);
DISPLAY INVISIBLE (3825 -750);
FORCEPROP 0 LAST $SEC 1
J 0
(3825 -750);
DISPLAY INVISIBLE (3825 -750);
FORCEPROP 0 LAST CDS_SEC 1
J 0
(3825 -750);
DISPLAY INVISIBLE (3825 -750);
FORCEPROP 1 LASTPIN (3775 -800) $PN 1
J 0
(3785 -820);
DISPLAY 0.787234 (3785 -820);
PAINT MONO (3785 -820);
DISPLAY INVISIBLE (3785 -820);
FORCEPROP 1 LASTPIN (3775 -1000) $PN 2
J 0
(3785 -1020);
DISPLAY 0.787234 (3785 -1020);
PAINT MONO (3785 -1020);
DISPLAY INVISIBLE (3785 -1020);
FORCEADD UNIVERSAL_POWER..1
R 2
(3775 -600);
FORCEPROP 3 LASTPIN (3775 -650) SIG_NAME P3V3_E1S_0_R\g
J 0
(3785 -640);
DISPLAY 0.659574 (3785 -640);
PAINT MONO (3785 -640);
DISPLAY INVISIBLE (3785 -640);
FORCEPROP 1 LAST HDL_POWER P3V3_E1S_0_R
J 1
(3775 -550);
DISPLAY 0.723404 (3775 -550);
PAINT GREEN (3775 -550);
FORCEPROP 2 LAST CDS_LIB logical_power
J 0
(3775 -600);
DISPLAY INVISIBLE (3775 -600);
FORCEPROP 1 LAST PATH I54
J 2
(3725 -575);
DISPLAY 0.872340 (3725 -575);
PAINT AQUA (3725 -575);
DISPLAY INVISIBLE (3725 -575);
FORCEADD UNIVERSAL_POWER..1
R 2
(3750 -575);
FORCEPROP 1 LAST HDL_POWER P3V3_E1S_0_R
J 1
(3750 -525);
DISPLAY 0.510638 (3750 -525);
PAINT GREEN (3750 -525);
FORCEPROP 2 LAST CDS_LIB logical_power
J 0
(3750 -575);
DISPLAY INVISIBLE (3750 -575);
FORCEPROP 1 LAST PATH I55
J 2
(3700 -550);
DISPLAY 0.872340 (3700 -550);
PAINT AQUA (3700 -550);
DISPLAY INVISIBLE (3700 -550);
FORCEADD GND..1
(175 825);
FORCEPROP 3 LASTPIN (175 875) SIG_NAME GND\g
J 0
(185 885);
DISPLAY 0.659574 (185 885);
PAINT MONO (185 885);
DISPLAY INVISIBLE (185 885);
FORCEPROP 2 LAST CDS_LIB logical_power
J 0
(175 825);
DISPLAY INVISIBLE (175 825);
FORCEPROP 1 LAST SIZE 1B
J 0
(250 775);
DISPLAY 0.872340 (250 775);
PAINT GREEN (250 775);
DISPLAY INVISIBLE (250 775);
FORCEPROP 1 LAST HDL_POWER GND
J 0
(175 975);
DISPLAY 0.872340 (175 975);
PAINT GREEN (175 975);
DISPLAY INVISIBLE (175 975);
FORCEPROP 1 LAST PATH I56
J 0
(250 825);
DISPLAY 0.872340 (250 825);
PAINT AQUA (250 825);
DISPLAY INVISIBLE (250 825);
FORCEADD Q_CAP..1
R 1
(400 900);
FORCEPROP 1 LAST PART_NUMBER CH5104KEB02
J 0
(450 850);
DISPLAY 0.510638 (450 850);
DISPLAY INVISIBLE (450 850);
FORCEPROP 1 LAST VOLTAGE 25V
J 0
(550 950);
DISPLAY 0.510638 (550 950);
FORCEPROP 1 LAST PACK_TYPE C0402
J 0
(225 850);
DISPLAY 0.510638 (225 850);
FORCEPROP 1 LAST MATERIAL EMPTY
J 0
(325 825);
DISPLAY 0.510638 (325 825);
PAINT RED (325 825);
FORCEPROP 1 LAST VALUE 1UF
J 0
(375 950);
DISPLAY 0.510638 (375 950);
FORCEPROP 2 LAST ROOM E1S1_P12V_MAM_MAM_BOM1
J 0
(225 975);
DISPLAY 0.510638 (225 975);
FORCEPROP 1 LAST LOCATION PC2211
J 0
(225 950);
DISPLAY 0.510638 (225 950);
FORCEPROP 1 LASTPIN (300 900) $PN 1
R 1
J 0
(320 910);
DISPLAY 0.510638 (320 910);
PAINT MONO (320 910);
FORCEPROP 1 LASTPIN (500 900) $PN 2
R 1
J 0
(520 910);
DISPLAY 0.510638 (520 910);
PAINT MONO (520 910);
FORCEPROP 2 LAST ROOM1 E1S1_P12V_MAM_TIC_BOM2
J 0
(225 1050);
DISPLAY 1.021277 (225 1050);
DISPLAY INVISIBLE (225 1050);
FORCEPROP 2 LAST CDS_LIB pure_quanta
J 0
(400 900);
DISPLAY INVISIBLE (400 900);
FORCEPROP 1 LAST TOLERANCE 10%
R 1
J 0
(450 950);
DISPLAY 0.638298 (450 950);
DISPLAY INVISIBLE (450 950);
FORCEPROP 1 LAST PATH I57
R 1
J 0
(250 950);
DISPLAY 0.978723 (250 950);
PAINT WHITE (250 950);
DISPLAY INVISIBLE (250 950);
FORCEPROP 0 LAST $SEC 1
R 1
J 0
(225 1000);
DISPLAY 0.680851 (225 1000);
PAINT MONO (225 1000);
DISPLAY INVISIBLE (225 1000);
FORCEPROP 0 LAST CDS_SEC 1
R 1
J 0
(225 1000);
DISPLAY 1.021277 (225 1000);
DISPLAY INVISIBLE (225 1000);
FORCEADD GND..1
(700 100);
FORCEPROP 3 LASTPIN (700 150) SIG_NAME GND\g
J 0
(710 160);
DISPLAY 0.659574 (710 160);
PAINT MONO (710 160);
DISPLAY INVISIBLE (710 160);
FORCEPROP 2 LAST CDS_LIB logical_power
J 0
(700 100);
DISPLAY INVISIBLE (700 100);
FORCEPROP 1 LAST SIZE 1B
J 0
(775 50);
DISPLAY 0.872340 (775 50);
PAINT GREEN (775 50);
DISPLAY INVISIBLE (775 50);
FORCEPROP 1 LAST HDL_POWER GND
J 0
(700 250);
DISPLAY 0.872340 (700 250);
PAINT GREEN (700 250);
DISPLAY INVISIBLE (700 250);
FORCEPROP 1 LAST PATH I58
J 0
(775 100);
DISPLAY 0.872340 (775 100);
PAINT AQUA (775 100);
DISPLAY INVISIBLE (775 100);
FORCEADD Q_RES..2
(700 400);
FORCEPROP 1 LAST PART_NUMBER CS29312FB02
J 0
(750 325);
DISPLAY 0.510638 (750 325);
DISPLAY INVISIBLE (750 325);
FORCEPROP 1 LAST PACK_TYPE 0402LF
J 0
(750 300);
DISPLAY 0.510638 (750 300);
FORCEPROP 1 LAST TOLERANCE 1%
J 0
(750 400);
DISPLAY 0.510638 (750 400);
FORCEPROP 1 LAST VALUE 9.31K
J 0
(750 425);
DISPLAY 0.510638 (750 425);
FORCEPROP 1 LAST MATERIAL EMPTY
J 0
(750 350);
DISPLAY 0.510638 (750 350);
PAINT RED (750 350);
FORCEPROP 1 LAST WATTAGE 1/16W
J 0
(750 375);
DISPLAY 0.510638 (750 375);
FORCEPROP 2 LAST ROOM E1S1_P12V_MAM_MAM_BOM1
J 0
(750 500);
DISPLAY 0.510638 (750 500);
FORCEPROP 1 LAST LOCATION PR3968
J 0
(750 450);
DISPLAY 0.510638 (750 450);
FORCEPROP 1 LASTPIN (700 500) $PN 1
J 0
(705 462);
DISPLAY 0.510638 (705 462);
PAINT MONO (705 462);
FORCEPROP 1 LASTPIN (700 300) $PN 2
J 0
(705 310);
DISPLAY 0.510638 (705 310);
PAINT MONO (705 310);
FORCEPROP 2 LAST ROOM1 E1S1_P12V_MAM_TIC_BOM2
J 0
(750 550);
DISPLAY 1.021277 (750 550);
DISPLAY INVISIBLE (750 550);
FORCEPROP 2 LAST CDS_LIB pure_quanta
J 0
(700 400);
DISPLAY INVISIBLE (700 400);
FORCEPROP 1 LAST PATH I59
J 0
(750 575);
DISPLAY 0.978723 (750 575);
PAINT WHITE (750 575);
DISPLAY INVISIBLE (750 575);
FORCEPROP 0 LAST $SEC 1
J 0
(750 550);
DISPLAY 0.680851 (750 550);
PAINT MONO (750 550);
DISPLAY INVISIBLE (750 550);
FORCEPROP 0 LAST CDS_SEC 1
J 0
(750 525);
DISPLAY INVISIBLE (750 525);
FORCEADD Q_RES..2
(-3150 -1775);
FORCEPROP 1 LAST PART_NUMBER CS31002FB08
J 0
(-3120 -1858);
DISPLAY 0.638298 (-3120 -1858);
DISPLAY INVISIBLE (-3120 -1858);
FORCEPROP 1 LAST VALUE 10K
J 0
(-3115 -1658);
DISPLAY 0.638298 (-3115 -1658);
FORCEPROP 1 LAST TOLERANCE 1%
J 0
(-3115 -1708);
DISPLAY 0.638298 (-3115 -1708);
FORCEPROP 1 LAST PACK_TYPE 0402LF
J 0
(-3120 -1908);
DISPLAY 0.638298 (-3120 -1908);
FORCEPROP 1 LAST WATTAGE 1/16W
J 0
(-3120 -1758);
DISPLAY 0.638298 (-3120 -1758);
FORCEPROP 1 LAST MATERIAL CHIP
J 0
(-3120 -1808);
DISPLAY 0.638298 (-3120 -1808);
FORCEPROP 2 LAST ROOM E1S1_P3V3_BOM1
J 0
(-3100 -1575);
DISPLAY 0.808511 (-3100 -1575);
FORCEPROP 1 LAST $LOCATION R4072
J 0
(-3115 -1608);
DISPLAY 0.638298 (-3115 -1608);
FORCEPROP 1 LASTPIN (-3150 -1675) $PN 1
J 0
(-3145 -1713);
DISPLAY 0.787234 (-3145 -1713);
PAINT MONO (-3145 -1713);
FORCEPROP 1 LASTPIN (-3150 -1875) $PN 2
J 0
(-3145 -1865);
DISPLAY 0.787234 (-3145 -1865);
PAINT MONO (-3145 -1865);
FORCEPROP 2 LAST CDS_LIB pure_quanta
J 0
(-3150 -1775);
DISPLAY INVISIBLE (-3150 -1775);
FORCEPROP 1 LAST PATH I6
J 0
(-3100 -1600);
DISPLAY 0.978723 (-3100 -1600);
PAINT WHITE (-3100 -1600);
DISPLAY INVISIBLE (-3100 -1600);
FORCEPROP 0 LAST CDS_LOCATION R4072
J 0
(-3100 -1575);
DISPLAY 1.021277 (-3100 -1575);
DISPLAY INVISIBLE (-3100 -1575);
FORCEPROP 0 LAST $SEC 1
J 0
(-3100 -1575);
DISPLAY 0.680851 (-3100 -1575);
PAINT MONO (-3100 -1575);
DISPLAY INVISIBLE (-3100 -1575);
FORCEPROP 0 LAST CDS_SEC 1
J 0
(-3100 -1575);
DISPLAY 1.021277 (-3100 -1575);
DISPLAY INVISIBLE (-3100 -1575);
FORCEADD Q_CAP..1
(175 1200);
FORCEPROP 1 LAST PART_NUMBER CH5104KEB02
J 0
(225 1100);
DISPLAY 0.510638 (225 1100);
DISPLAY INVISIBLE (225 1100);
FORCEPROP 1 LAST VALUE 1UF
J 0
(225 1200);
DISPLAY 0.510638 (225 1200);
FORCEPROP 1 LAST VOLTAGE 25V
J 0
(225 1150);
DISPLAY 0.510638 (225 1150);
FORCEPROP 1 LAST PACK_TYPE C0402
J 0
(225 1125);
DISPLAY 0.510638 (225 1125);
FORCEPROP 1 LAST MATERIAL EMPTY
J 0
(225 1175);
DISPLAY 0.510638 (225 1175);
PAINT RED (225 1175);
FORCEPROP 2 LAST ROOM E1S1_P12V_MAM_MAM_BOM1
J 0
(225 1275);
DISPLAY 0.510638 (225 1275);
FORCEPROP 1 LAST LOCATION PC2209
J 0
(225 1225);
DISPLAY 0.510638 (225 1225);
FORCEPROP 1 LASTPIN (175 1300) $PN 1
J 0
(185 1280);
DISPLAY 0.510638 (185 1280);
PAINT MONO (185 1280);
FORCEPROP 1 LASTPIN (175 1100) $PN 2
J 0
(185 1080);
DISPLAY 0.510638 (185 1080);
PAINT MONO (185 1080);
FORCEPROP 2 LAST ROOM1 E1S1_P12V_MAM_TIC_BOM2
J 0
(225 1325);
DISPLAY 1.021277 (225 1325);
DISPLAY INVISIBLE (225 1325);
FORCEPROP 2 LAST CDS_LIB pure_quanta
J 0
(175 1200);
DISPLAY INVISIBLE (175 1200);
FORCEPROP 1 LAST TOLERANCE 10%
J 0
(225 1150);
DISPLAY 0.638298 (225 1150);
DISPLAY INVISIBLE (225 1150);
FORCEPROP 1 LAST PATH I60
J 0
(225 1350);
DISPLAY 0.978723 (225 1350);
PAINT WHITE (225 1350);
DISPLAY INVISIBLE (225 1350);
FORCEPROP 0 LAST $SEC 1
J 0
(225 1275);
DISPLAY 0.680851 (225 1275);
PAINT MONO (225 1275);
DISPLAY INVISIBLE (225 1275);
FORCEPROP 0 LAST CDS_SEC 1
J 0
(225 1275);
DISPLAY 1.021277 (225 1275);
DISPLAY INVISIBLE (225 1275);
FORCEADD Q_RES..2
(175 1625);
FORCEPROP 1 LAST PART_NUMBER CS01002FB07
J 0
(225 1575);
DISPLAY 0.510638 (225 1575);
DISPLAY INVISIBLE (225 1575);
FORCEPROP 1 LAST TOLERANCE 1%
J 0
(225 1650);
DISPLAY 0.510638 (225 1650);
FORCEPROP 1 LAST VALUE 10
J 0
(225 1675);
DISPLAY 0.510638 (225 1675);
FORCEPROP 1 LAST WATTAGE 1/16W
J 0
(225 1625);
DISPLAY 0.510638 (225 1625);
FORCEPROP 1 LAST MATERIAL EMPTY
J 0
(225 1600);
DISPLAY 0.510638 (225 1600);
PAINT RED (225 1600);
FORCEPROP 2 LAST ROOM E1S1_P12V_MAM_MAM_BOM1
J 0
(225 1750);
DISPLAY 0.510638 (225 1750);
FORCEPROP 1 LAST PACK_TYPE 0402LF
J 0
(225 1550);
DISPLAY 0.510638 (225 1550);
FORCEPROP 1 LAST LOCATION PR3966
J 0
(225 1700);
DISPLAY 0.510638 (225 1700);
FORCEPROP 1 LASTPIN (175 1725) $PN 1
J 0
(180 1687);
DISPLAY 0.510638 (180 1687);
PAINT MONO (180 1687);
FORCEPROP 1 LASTPIN (175 1525) $PN 2
J 0
(180 1535);
DISPLAY 0.510638 (180 1535);
PAINT MONO (180 1535);
FORCEPROP 2 LAST ROOM1 E1S1_P12V_MAM_TIC_BOM2
J 0
(225 1800);
DISPLAY 1.021277 (225 1800);
DISPLAY INVISIBLE (225 1800);
FORCEPROP 2 LAST CDS_LIB pure_quanta
J 0
(175 1625);
DISPLAY INVISIBLE (175 1625);
FORCEPROP 1 LAST PATH I61
J 0
(225 1800);
DISPLAY 0.978723 (225 1800);
PAINT WHITE (225 1800);
DISPLAY INVISIBLE (225 1800);
FORCEPROP 0 LAST $SEC 1
J 0
(225 1750);
DISPLAY 0.680851 (225 1750);
PAINT MONO (225 1750);
DISPLAY INVISIBLE (225 1750);
FORCEPROP 0 LAST CDS_SEC 1
J 0
(225 1750);
DISPLAY 1.021277 (225 1750);
DISPLAY INVISIBLE (225 1750);
FORCEADD MAX15090BEWIT..1
(1450 900);
FORCEPROP 1 LAST PART_NUMBER AL015080B00
J 0
(1197 1544);
DISPLAY 0.510638 (1197 1544);
PAINT GREEN (1197 1544);
DISPLAY INVISIBLE (1197 1544);
FORCEPROP 2 LAST PART_TYPE SMLF
J 0
(1200 1725);
DISPLAY 0.510638 (1200 1725);
FORCEPROP 2 LAST VALUE MAX15090BEWI+T
J 0
(1200 1675);
DISPLAY 0.510638 (1200 1675);
FORCEPROP 2 LAST ROOM E1S1_P12V_MAM_MAM_BOM1
J 0
(1200 1775);
DISPLAY 0.510638 (1200 1775);
FORCEPROP 1 LAST MATERIAL EMPTY
J 0
(1197 1455);
DISPLAY 0.510638 (1197 1455);
PAINT RED (1197 1455);
FORCEPROP 1 LAST LOCATION PU294
J 0
(1200 1850);
DISPLAY 0.510638 (1200 1850);
PAINT GREEN (1200 1850);
FORCEPROP 0 LASTPIN (1050 600) $PN B1
J 2
(1040 610);
DISPLAY 0.510638 (1040 610);
PAINT MONO (1040 610);
FORCEPROP 0 LASTPIN (1850 600) $PN A7
J 0
(1860 610);
DISPLAY 0.510638 (1860 610);
PAINT MONO (1860 610);
FORCEPROP 0 LASTPIN (1050 500) $PN B7
J 2
(1040 510);
DISPLAY 0.510638 (1040 510);
PAINT MONO (1040 510);
FORCEPROP 0 LASTPIN (1850 800) $PN C7
J 0
(1860 810);
DISPLAY 0.510638 (1860 810);
PAINT MONO (1860 810);
FORCEPROP 0 LASTPIN (1850 1000) $PN A6
J 0
(1860 1010);
DISPLAY 0.510638 (1860 1010);
PAINT MONO (1860 1010);
FORCEPROP 0 LASTPIN (1850 500) $PN B2
J 0
(1860 510);
DISPLAY 0.510638 (1860 510);
PAINT MONO (1860 510);
FORCEPROP 0 LASTPIN (1850 450) $PN C1
J 0
(1860 460);
DISPLAY 0.510638 (1860 460);
PAINT MONO (1860 460);
FORCEPROP 0 LASTPIN (1850 400) $PN C2
J 0
(1860 410);
DISPLAY 0.510638 (1860 410);
PAINT MONO (1860 410);
FORCEPROP 0 LASTPIN (1050 1400) $PN A3
J 2
(1040 1410);
DISPLAY 0.510638 (1040 1410);
PAINT MONO (1040 1410);
FORCEPROP 0 LASTPIN (1050 1350) $PN A5
J 2
(1040 1360);
DISPLAY 0.510638 (1040 1360);
PAINT MONO (1040 1360);
FORCEPROP 0 LASTPIN (1050 1300) $PN B3
J 2
(1040 1310);
DISPLAY 0.510638 (1040 1310);
PAINT MONO (1040 1310);
FORCEPROP 0 LASTPIN (1050 1250) $PN B5
J 2
(1040 1260);
DISPLAY 0.510638 (1040 1260);
PAINT MONO (1040 1260);
FORCEPROP 0 LASTPIN (1050 1200) $PN C3
J 2
(1040 1210);
DISPLAY 0.510638 (1040 1210);
PAINT MONO (1040 1210);
FORCEPROP 0 LASTPIN (1050 1150) $PN C5
J 2
(1040 1160);
DISPLAY 0.510638 (1040 1160);
PAINT MONO (1040 1160);
FORCEPROP 0 LASTPIN (1050 1100) $PN D5
J 2
(1040 1110);
DISPLAY 0.510638 (1040 1110);
PAINT MONO (1040 1110);
FORCEPROP 0 LASTPIN (1850 700) $PN A1
J 0
(1860 710);
DISPLAY 0.510638 (1860 710);
PAINT MONO (1860 710);
FORCEPROP 0 LASTPIN (1850 1400) $PN A4
J 0
(1860 1410);
DISPLAY 0.510638 (1860 1410);
PAINT MONO (1860 1410);
FORCEPROP 0 LASTPIN (1850 1350) $PN B4
J 0
(1860 1360);
DISPLAY 0.510638 (1860 1360);
PAINT MONO (1860 1360);
FORCEPROP 0 LASTPIN (1850 1300) $PN B6
J 0
(1860 1310);
DISPLAY 0.510638 (1860 1310);
PAINT MONO (1860 1310);
FORCEPROP 0 LASTPIN (1850 1250) $PN C4
J 0
(1860 1260);
DISPLAY 0.510638 (1860 1260);
PAINT MONO (1860 1260);
FORCEPROP 0 LASTPIN (1850 1200) $PN C6
J 0
(1860 1210);
DISPLAY 0.510638 (1860 1210);
PAINT MONO (1860 1210);
FORCEPROP 0 LASTPIN (1850 1150) $PN D4
J 0
(1860 1160);
DISPLAY 0.510638 (1860 1160);
PAINT MONO (1860 1160);
FORCEPROP 0 LASTPIN (1850 1100) $PN D6
J 0
(1860 1110);
DISPLAY 0.510638 (1860 1110);
PAINT MONO (1860 1110);
FORCEPROP 0 LASTPIN (1050 700) $PN D3
J 2
(1040 710);
DISPLAY 0.510638 (1040 710);
PAINT MONO (1040 710);
FORCEPROP 0 LASTPIN (1850 900) $PN D7
J 0
(1860 910);
DISPLAY 0.510638 (1860 910);
PAINT MONO (1860 910);
FORCEPROP 0 LASTPIN (1050 900) $PN D1
J 2
(1040 910);
DISPLAY 0.510638 (1040 910);
PAINT MONO (1040 910);
FORCEPROP 0 LASTPIN (1050 800) $PN D2
J 2
(1040 810);
DISPLAY 0.510638 (1040 810);
PAINT MONO (1040 810);
FORCEPROP 0 LASTPIN (1050 1000) $PN A2
J 2
(1040 1010);
DISPLAY 0.510638 (1040 1010);
PAINT MONO (1040 1010);
FORCEPROP 2 LAST ROOM1 E1S1_P12V_MAM_TIC_BOM2
J 0
(1200 1825);
DISPLAY 1.021277 (1200 1825);
DISPLAY INVISIBLE (1200 1825);
FORCEPROP 1 LAST PIN_NAMES_ROTATE TRUE
J 0
(1450 900);
DISPLAY 0.489362 (1450 900);
PAINT GREEN (1450 900);
DISPLAY INVISIBLE (1450 900);
FORCEPROP 2 LAST CDS_LIB pure_quanta
J 0
(1450 900);
DISPLAY INVISIBLE (1450 900);
FORCEPROP 1 LAST CDS_LMAN_SYM_OUTLINE -250,550,250,-550
J 0
(1450 900);
DISPLAY 0.468085 (1450 900);
PAINT GREEN (1450 900);
DISPLAY INVISIBLE (1450 900);
FORCEPROP 1 LAST PATH I62
J 0
(1700 350);
DISPLAY 0.723404 (1700 350);
PAINT GREEN (1700 350);
DISPLAY INVISIBLE (1700 350);
FORCEPROP 0 LAST $SEC 1
J 0
(1200 1775);
DISPLAY 0.680851 (1200 1775);
PAINT MONO (1200 1775);
DISPLAY INVISIBLE (1200 1775);
FORCEPROP 0 LAST CDS_SEC 1
J 0
(1200 1775);
DISPLAY 1.021277 (1200 1775);
DISPLAY INVISIBLE (1200 1775);
FORCEADD GND..1
(2175 225);
FORCEPROP 3 LASTPIN (2175 275) SIG_NAME GND\g
J 0
(2185 285);
DISPLAY 0.659574 (2185 285);
PAINT MONO (2185 285);
DISPLAY INVISIBLE (2185 285);
FORCEPROP 1 LAST SIZE 1B
J 0
(2250 175);
DISPLAY 0.872340 (2250 175);
PAINT GREEN (2250 175);
DISPLAY INVISIBLE (2250 175);
FORCEPROP 2 LAST CDS_LIB logical_power
J 0
(2175 225);
DISPLAY INVISIBLE (2175 225);
FORCEPROP 1 LAST HDL_POWER GND
J 0
(2175 375);
DISPLAY 0.872340 (2175 375);
PAINT GREEN (2175 375);
DISPLAY INVISIBLE (2175 375);
FORCEPROP 1 LAST PATH I63
J 0
(2250 225);
DISPLAY 0.872340 (2250 225);
PAINT AQUA (2250 225);
DISPLAY INVISIBLE (2250 225);
FORCEADD Q_RES..2
(2300 525);
FORCEPROP 1 LAST PART_NUMBER CS22672FB03
J 0
(2350 450);
DISPLAY 0.510638 (2350 450);
DISPLAY INVISIBLE (2350 450);
FORCEPROP 1 LAST TOLERANCE 1%
J 0
(2350 525);
DISPLAY 0.510638 (2350 525);
FORCEPROP 1 LAST VALUE 2.67K
J 0
(2350 550);
DISPLAY 0.510638 (2350 550);
FORCEPROP 1 LAST WATTAGE 1/16W
J 0
(2350 500);
DISPLAY 0.510638 (2350 500);
FORCEPROP 1 LAST MATERIAL EMPTY
J 0
(2350 475);
DISPLAY 0.510638 (2350 475);
PAINT RED (2350 475);
FORCEPROP 1 LAST PACK_TYPE 0402LF
J 0
(2350 425);
DISPLAY 0.510638 (2350 425);
FORCEPROP 2 LAST ROOM E1S1_P12V_MAM_MAM_BOM1
J 0
(2325 375);
DISPLAY 0.510638 (2325 375);
FORCEPROP 1 LAST LOCATION PR3970
J 0
(2350 575);
DISPLAY 0.510638 (2350 575);
FORCEPROP 1 LASTPIN (2300 625) $PN 1
J 0
(2305 587);
DISPLAY 0.510638 (2305 587);
PAINT MONO (2305 587);
FORCEPROP 1 LASTPIN (2300 425) $PN 2
J 0
(2305 435);
DISPLAY 0.510638 (2305 435);
PAINT MONO (2305 435);
FORCEPROP 2 LAST ROOM1 E1S1_P12V_MAM_TIC_BOM2
J 0
(2350 575);
DISPLAY 1.021277 (2350 575);
DISPLAY INVISIBLE (2350 575);
FORCEPROP 2 LAST CDS_LIB pure_quanta
J 0
(2300 525);
DISPLAY INVISIBLE (2300 525);
FORCEPROP 1 LAST PATH I64
J 0
(2350 700);
DISPLAY 0.978723 (2350 700);
PAINT WHITE (2350 700);
DISPLAY INVISIBLE (2350 700);
FORCEPROP 0 LAST $SEC 1
J 0
(2350 700);
DISPLAY 0.680851 (2350 700);
PAINT MONO (2350 700);
DISPLAY INVISIBLE (2350 700);
FORCEPROP 0 LAST CDS_SEC 1
J 0
(2350 700);
DISPLAY 1.021277 (2350 700);
DISPLAY INVISIBLE (2350 700);
FORCEADD Q_RES..1
(3075 475);
FORCEPROP 1 LAST PART_NUMBER CS00002JB13
J 0
(2900 425);
DISPLAY 0.510638 (2900 425);
DISPLAY INVISIBLE (2900 425);
FORCEPROP 1 LAST WATTAGE 1/16W
J 2
(2875 425);
DISPLAY 0.510638 (2875 425);
FORCEPROP 1 LAST MATERIAL EMPTY
J 0
(2850 475);
DISPLAY 0.510638 (2850 475);
PAINT RED (2850 475);
FORCEPROP 1 LAST VALUE 0
J 2
(3225 475);
DISPLAY 0.510638 (3225 475);
FORCEPROP 0 LAST ROOM1 E1S1_P12V_MAM_TIC_BOM2
J 0
(2850 325);
DISPLAY 0.510638 (2850 325);
FORCEPROP 1 LAST TOLERANCE 5%
J 0
(3250 475);
DISPLAY 0.510638 (3250 475);
FORCEPROP 1 LAST PACK_TYPE 0402LF
J 0
(3225 425);
DISPLAY 0.510638 (3225 425);
FORCEPROP 1 LAST $LOCATION R3975
J 0
(3025 525);
DISPLAY 0.510638 (3025 525);
FORCEPROP 1 LASTPIN (2975 475) $PN 1
J 0
(2987 487);
DISPLAY 0.510638 (2987 487);
PAINT MONO (2987 487);
FORCEPROP 1 LASTPIN (3175 475) $PN 2
J 0
(3137 487);
DISPLAY 0.510638 (3137 487);
PAINT MONO (3137 487);
FORCEPROP 2 LAST CDS_LIB pure_quanta
J 0
(3075 475);
DISPLAY INVISIBLE (3075 475);
FORCEPROP 1 LAST PATH I65
J 0
(3025 625);
DISPLAY 0.978723 (3025 625);
PAINT WHITE (3025 625);
DISPLAY INVISIBLE (3025 625);
FORCEPROP 0 LAST CDS_LOCATION R3975
J 0
(3025 575);
DISPLAY 1.021277 (3025 575);
DISPLAY INVISIBLE (3025 575);
FORCEPROP 0 LAST $SEC 1
J 0
(3025 575);
DISPLAY 0.680851 (3025 575);
PAINT MONO (3025 575);
DISPLAY INVISIBLE (3025 575);
FORCEPROP 0 LAST CDS_SEC 1
J 0
(3025 575);
DISPLAY 1.021277 (3025 575);
DISPLAY INVISIBLE (3025 575);
FORCEADD Q_CAP..1
R 1
(2800 1000);
FORCEPROP 1 LAST PART_NUMBER CH23906KB14
J 0
(2950 1025);
DISPLAY 0.510638 (2950 1025);
DISPLAY INVISIBLE (2950 1025);
FORCEPROP 1 LAST VALUE 3900PF
J 0
(2725 1050);
DISPLAY 0.510638 (2725 1050);
FORCEPROP 1 LAST MATERIAL EMPTY
J 0
(2875 950);
DISPLAY 0.510638 (2875 950);
PAINT RED (2875 950);
FORCEPROP 1 LAST VOLTAGE 50V
J 0
(2925 1075);
DISPLAY 0.510638 (2925 1075);
FORCEPROP 2 LAST ROOM E1S1_P12V_MAM_MAM_BOM1
J 0
(2925 1125);
DISPLAY 0.510638 (2925 1125);
FORCEPROP 1 LAST PACK_TYPE C0402
J 0
(2575 950);
DISPLAY 0.510638 (2575 950);
FORCEPROP 1 LAST LOCATION PC2215
J 0
(2525 1000);
DISPLAY 0.510638 (2525 1000);
FORCEPROP 1 LASTPIN (2700 1000) $PN 1
R 1
J 0
(2720 1010);
DISPLAY 0.510638 (2720 1010);
PAINT MONO (2720 1010);
FORCEPROP 1 LASTPIN (2900 1000) $PN 2
R 1
J 0
(2920 1010);
DISPLAY 0.510638 (2920 1010);
PAINT MONO (2920 1010);
FORCEPROP 2 LAST ROOM1 E1S1_P12V_MAM_TIC_BOM2
J 0
(2925 1175);
DISPLAY 1.021277 (2925 1175);
DISPLAY INVISIBLE (2925 1175);
FORCEPROP 2 LAST CDS_LIB pure_quanta
R 1
J 0
(2800 1000);
DISPLAY INVISIBLE (2800 1000);
FORCEPROP 1 LAST TOLERANCE 10%
R 1
J 0
(2850 1050);
DISPLAY 0.638298 (2850 1050);
DISPLAY INVISIBLE (2850 1050);
FORCEPROP 1 LAST PATH I66
R 1
J 0
(2650 1050);
DISPLAY 0.978723 (2650 1050);
PAINT WHITE (2650 1050);
DISPLAY INVISIBLE (2650 1050);
FORCEPROP 0 LAST $SEC 1
R 1
J 0
(2900 1125);
DISPLAY 0.680851 (2900 1125);
PAINT MONO (2900 1125);
DISPLAY INVISIBLE (2900 1125);
FORCEPROP 0 LAST CDS_SEC 1
R 1
J 0
(2900 1125);
DISPLAY 1.021277 (2900 1125);
DISPLAY INVISIBLE (2900 1125);
FORCEADD Q_RES..1
(3075 700);
FORCEPROP 1 LAST PART_NUMBER CS00002JB13
J 0
(2900 650);
DISPLAY 0.510638 (2900 650);
DISPLAY INVISIBLE (2900 650);
FORCEPROP 1 LAST WATTAGE 1/16W
J 2
(2875 650);
DISPLAY 0.510638 (2875 650);
FORCEPROP 1 LAST MATERIAL EMPTY
J 0
(2850 700);
DISPLAY 0.510638 (2850 700);
PAINT RED (2850 700);
FORCEPROP 1 LAST VALUE 0
J 2
(3225 700);
DISPLAY 0.510638 (3225 700);
FORCEPROP 1 LAST TOLERANCE 5%
J 0
(3250 700);
DISPLAY 0.510638 (3250 700);
FORCEPROP 1 LAST PACK_TYPE 0402LF
J 0
(3225 650);
DISPLAY 0.510638 (3225 650);
FORCEPROP 2 LAST ROOM E1S1_P12V_MAM_MAM_BOM1
J 0
(2825 775);
DISPLAY 0.510638 (2825 775);
FORCEPROP 1 LAST LOCATION R3974
J 0
(3025 750);
DISPLAY 0.510638 (3025 750);
FORCEPROP 1 LASTPIN (2975 700) $PN 1
J 0
(2987 712);
DISPLAY 0.510638 (2987 712);
PAINT MONO (2987 712);
FORCEPROP 1 LASTPIN (3175 700) $PN 2
J 0
(3137 712);
DISPLAY 0.510638 (3137 712);
PAINT MONO (3137 712);
FORCEPROP 2 LAST CDS_LIB pure_quanta
J 0
(3075 700);
DISPLAY INVISIBLE (3075 700);
FORCEPROP 1 LAST PATH I67
J 0
(3025 850);
DISPLAY 0.978723 (3025 850);
PAINT WHITE (3025 850);
DISPLAY INVISIBLE (3025 850);
FORCEPROP 0 LAST $SEC 1
J 0
(3025 800);
DISPLAY 0.680851 (3025 800);
PAINT MONO (3025 800);
DISPLAY INVISIBLE (3025 800);
FORCEPROP 0 LAST CDS_SEC 1
J 0
(3025 800);
DISPLAY 1.021277 (3025 800);
DISPLAY INVISIBLE (3025 800);
FORCEADD Q_RES..1
(2925 900);
FORCEPROP 1 LAST PART_NUMBER CS00002JB13
J 0
(2750 850);
DISPLAY 0.510638 (2750 850);
DISPLAY INVISIBLE (2750 850);
FORCEPROP 1 LAST MATERIAL EMPTY
J 0
(2700 900);
DISPLAY 0.510638 (2700 900);
PAINT RED (2700 900);
FORCEPROP 1 LAST VALUE 0
J 2
(3075 900);
DISPLAY 0.510638 (3075 900);
FORCEPROP 1 LAST TOLERANCE 5%
J 0
(3100 900);
DISPLAY 0.510638 (3100 900);
FORCEPROP 1 LAST PACK_TYPE 0402LF
J 0
(3075 850);
DISPLAY 0.510638 (3075 850);
FORCEPROP 2 LAST ROOM E1S1_P12V_MAM_MAM_BOM1
J 0
(3100 950);
DISPLAY 0.510638 (3100 950);
FORCEPROP 1 LAST WATTAGE 1/16W
J 2
(2725 850);
DISPLAY 0.510638 (2725 850);
FORCEPROP 1 LAST $LOCATION R3972
J 0
(2575 900);
DISPLAY 0.510638 (2575 900);
FORCEPROP 1 LASTPIN (2825 900) $PN 1
J 0
(2837 912);
DISPLAY 0.510638 (2837 912);
PAINT MONO (2837 912);
FORCEPROP 1 LASTPIN (3025 900) $PN 2
J 0
(2987 912);
DISPLAY 0.510638 (2987 912);
PAINT MONO (2987 912);
FORCEPROP 2 LAST ROOM1 E1S1_P12V_MAM_TIC_BOM2
J 0
(3100 1000);
DISPLAY 1.021277 (3100 1000);
DISPLAY INVISIBLE (3100 1000);
FORCEPROP 2 LAST CDS_LIB pure_quanta
J 0
(2925 900);
DISPLAY INVISIBLE (2925 900);
FORCEPROP 1 LAST PATH I68
J 0
(2875 1050);
DISPLAY 0.978723 (2875 1050);
PAINT WHITE (2875 1050);
DISPLAY INVISIBLE (2875 1050);
FORCEPROP 0 LAST CDS_LOCATION R3972
J 0
(2875 975);
DISPLAY 1.021277 (2875 975);
DISPLAY INVISIBLE (2875 975);
FORCEPROP 0 LAST $SEC 1
J 0
(2875 975);
DISPLAY 0.680851 (2875 975);
PAINT MONO (2875 975);
DISPLAY INVISIBLE (2875 975);
FORCEPROP 0 LAST CDS_SEC 1
J 0
(2875 975);
DISPLAY 1.021277 (2875 975);
DISPLAY INVISIBLE (2875 975);
FORCEADD Q_CAP..1
(2250 1225);
FORCEPROP 1 LAST PART_NUMBER CH31006KB18
J 0
(2300 1175);
DISPLAY 0.510638 (2300 1175);
DISPLAY INVISIBLE (2300 1175);
FORCEPROP 1 LAST PACK_TYPE C0402
J 0
(2300 1150);
DISPLAY 0.510638 (2300 1150);
FORCEPROP 1 LAST VALUE 0.01UF
J 0
(2300 1250);
DISPLAY 0.510638 (2300 1250);
FORCEPROP 1 LAST VOLTAGE 50V
J 0
(2300 1225);
DISPLAY 0.510638 (2300 1225);
FORCEPROP 1 LAST MATERIAL EMPTY
J 0
(2300 1200);
DISPLAY 0.510638 (2300 1200);
PAINT RED (2300 1200);
FORCEPROP 1 LAST LOCATION PC2214
J 0
(2300 1275);
DISPLAY 0.510638 (2300 1275);
FORCEPROP 1 LASTPIN (2250 1325) $PN 1
J 0
(2260 1305);
DISPLAY 0.510638 (2260 1305);
PAINT MONO (2260 1305);
FORCEPROP 1 LASTPIN (2250 1125) $PN 2
J 0
(2260 1105);
DISPLAY 0.510638 (2260 1105);
PAINT MONO (2260 1105);
FORCEPROP 2 LAST CDS_LIB pure_quanta
J 0
(2250 1225);
DISPLAY INVISIBLE (2250 1225);
FORCEPROP 1 LAST TOLERANCE 10%
J 0
(2300 1175);
DISPLAY 0.638298 (2300 1175);
DISPLAY INVISIBLE (2300 1175);
FORCEPROP 1 LAST PATH I69
J 0
(2300 1375);
DISPLAY 0.978723 (2300 1375);
PAINT WHITE (2300 1375);
DISPLAY INVISIBLE (2300 1375);
FORCEPROP 0 LAST $SEC 1
J 0
(2300 1375);
DISPLAY 0.680851 (2300 1375);
PAINT MONO (2300 1375);
DISPLAY INVISIBLE (2300 1375);
FORCEPROP 0 LAST CDS_SEC 1
J 0
(2300 1375);
DISPLAY 1.021277 (2300 1375);
DISPLAY INVISIBLE (2300 1375);
FORCEADD UNIVERSAL_POWER..1
(-3150 -1525);
FORCEPROP 3 LASTPIN (-3150 -1575) SIG_NAME P12V_AUX\g
J 0
(-3140 -1565);
DISPLAY 0.659574 (-3140 -1565);
PAINT MONO (-3140 -1565);
DISPLAY INVISIBLE (-3140 -1565);
FORCEPROP 1 LAST HDL_POWER P12V_AUX
J 1
(-3150 -1475);
DISPLAY 0.872340 (-3150 -1475);
PAINT GREEN (-3150 -1475);
FORCEPROP 2 LAST CDS_LIB logical_power
J 0
(-3150 -1525);
DISPLAY INVISIBLE (-3150 -1525);
FORCEPROP 1 LAST PATH I7
J 0
(-3100 -1500);
DISPLAY 0.872340 (-3100 -1500);
PAINT AQUA (-3100 -1500);
DISPLAY INVISIBLE (-3100 -1500);
FORCEADD Q_RES..2
(2575 1250);
FORCEPROP 1 LAST PART_NUMBER CS61002FB02
J 0
(2600 1125);
DISPLAY 0.510638 (2600 1125);
DISPLAY INVISIBLE (2600 1125);
FORCEPROP 1 LAST VALUE 10M
J 0
(2600 1325);
DISPLAY 0.510638 (2600 1325);
FORCEPROP 1 LAST MATERIAL EMPTY
J 0
(2600 1175);
DISPLAY 0.510638 (2600 1175);
PAINT RED (2600 1175);
FORCEPROP 1 LAST PACK_TYPE 0402LF
J 0
(2600 1075);
DISPLAY 0.510638 (2600 1075);
FORCEPROP 1 LAST WATTAGE 1/16W
J 0
(2600 1225);
DISPLAY 0.510638 (2600 1225);
FORCEPROP 2 LAST ROOM E1S1_P12V_MAM_MAM_BOM1
J 0
(2600 1425);
DISPLAY 0.510638 (2600 1425);
FORCEPROP 1 LAST TOLERANCE 1%
J 0
(2600 1275);
DISPLAY 0.510638 (2600 1275);
FORCEPROP 1 LAST LOCATION PR4528
J 0
(2600 1375);
DISPLAY 0.510638 (2600 1375);
FORCEPROP 1 LASTPIN (2575 1350) $PN 1
J 0
(2580 1312);
DISPLAY 0.510638 (2580 1312);
PAINT MONO (2580 1312);
FORCEPROP 1 LASTPIN (2575 1150) $PN 2
J 0
(2580 1160);
DISPLAY 0.510638 (2580 1160);
PAINT MONO (2580 1160);
FORCEPROP 2 LAST ROOM1 E1S1_P12V_MAM_TIC_BOM2
J 0
(2600 1475);
DISPLAY 1.021277 (2600 1475);
DISPLAY INVISIBLE (2600 1475);
FORCEPROP 2 LAST CDS_LIB pure_quanta
J 0
(2575 1250);
DISPLAY INVISIBLE (2575 1250);
FORCEPROP 1 LAST PATH I70
J 0
(2625 1425);
DISPLAY 0.978723 (2625 1425);
PAINT WHITE (2625 1425);
DISPLAY INVISIBLE (2625 1425);
FORCEPROP 0 LAST $SEC 1
J 0
(2600 1425);
DISPLAY 0.680851 (2600 1425);
PAINT MONO (2600 1425);
DISPLAY INVISIBLE (2600 1425);
FORCEPROP 0 LAST CDS_SEC 1
J 0
(2600 1425);
DISPLAY 1.021277 (2600 1425);
DISPLAY INVISIBLE (2600 1425);
FORCEADD SCHOTTKY_AC..1
R 1
(2675 1850);
FORCEPROP 1 LAST PART_NUMBER BC000340Z30
J 0
(2725 1775);
DISPLAY 0.510638 (2725 1775);
PAINT GREEN (2725 1775);
DISPLAY INVISIBLE (2725 1775);
FORCEPROP 1 LAST MATERIAL IC
J 0
(2725 1750);
DISPLAY 0.510638 (2725 1750);
PAINT GREEN (2725 1750);
FORCEPROP 2 LAST VALUE B340A-13-F
J 0
(2725 1825);
DISPLAY 0.510638 (2725 1825);
FORCEPROP 1 LAST LOCATION PD112
J 0
(2725 1875);
DISPLAY 0.510638 (2725 1875);
PAINT GREEN (2725 1875);
FORCEPROP 0 LASTPIN (2675 1725) $PN A
R 1
J 2
(2665 1760);
DISPLAY 0.510638 (2665 1760);
FORCEPROP 0 LASTPIN (2675 1975) $PN C
R 1
J 0
(2665 1935);
DISPLAY 0.510638 (2665 1935);
FORCEPROP 1 LAST NEEDS_NO_SIZE TRUE
R 1
J 0
(2725 1925);
DISPLAY 0.468085 (2725 1925);
PAINT GREEN (2725 1925);
DISPLAY INVISIBLE (2725 1925);
FORCEPROP 1 LAST CDS_LMAN_SYM_OUTLINE -75,50,75,-50
R 1
J 0
(2675 1850);
DISPLAY 0.468085 (2675 1850);
PAINT GREEN (2675 1850);
DISPLAY INVISIBLE (2675 1850);
FORCEPROP 2 LAST CDS_LIB pure_quanta
R 1
J 0
(2675 1850);
DISPLAY INVISIBLE (2675 1850);
FORCEPROP 0 LAST PART_TYPE SMLF
J 0
(2725 2025);
DISPLAY 1.021277 (2725 2025);
DISPLAY INVISIBLE (2725 2025);
FORCEPROP 1 LAST PATH I71
R 1
J 0
(2675 1850);
DISPLAY 0.723404 (2675 1850);
PAINT GREEN (2675 1850);
DISPLAY INVISIBLE (2675 1850);
FORCEPROP 0 LAST $SEC 1
R 1
J 0
(2725 1925);
DISPLAY INVISIBLE (2725 1925);
FORCEPROP 0 LAST CDS_SEC 1
R 1
J 0
(2725 1925);
DISPLAY INVISIBLE (2725 1925);
FORCEADD GND..1
(3050 950);
FORCEPROP 3 LASTPIN (3050 1000) SIG_NAME GND\g
J 0
(3060 1010);
DISPLAY 0.659574 (3060 1010);
PAINT MONO (3060 1010);
DISPLAY INVISIBLE (3060 1010);
FORCEPROP 2 LAST CDS_LIB logical_power
J 0
(3050 950);
DISPLAY INVISIBLE (3050 950);
FORCEPROP 1 LAST SIZE 1B
J 0
(3125 900);
DISPLAY 0.872340 (3125 900);
PAINT GREEN (3125 900);
DISPLAY INVISIBLE (3125 900);
FORCEPROP 1 LAST HDL_POWER GND
J 0
(3050 1100);
DISPLAY 0.872340 (3050 1100);
PAINT GREEN (3050 1100);
DISPLAY INVISIBLE (3050 1100);
FORCEPROP 1 LAST PATH I72
J 0
(3125 950);
DISPLAY 0.872340 (3125 950);
PAINT AQUA (3125 950);
DISPLAY INVISIBLE (3125 950);
FORCEADD Q_RES..2
(3275 1150);
FORCEPROP 1 LAST PART_NUMBER CS41002FB09
J 0
(3315 1025);
DISPLAY 0.510638 (3315 1025);
DISPLAY INVISIBLE (3315 1025);
FORCEPROP 1 LAST PACK_TYPE 0402LF
J 0
(3315 975);
DISPLAY 0.510638 (3315 975);
FORCEPROP 1 LAST TOLERANCE 1%
J 0
(3320 1175);
DISPLAY 0.510638 (3320 1175);
FORCEPROP 1 LAST MATERIAL EMPTY
J 0
(3315 1075);
DISPLAY 0.510638 (3315 1075);
PAINT RED (3315 1075);
FORCEPROP 1 LAST WATTAGE 1/16W
J 0
(3315 1125);
DISPLAY 0.510638 (3315 1125);
FORCEPROP 1 LAST VALUE 100K
J 0
(3320 1225);
DISPLAY 0.510638 (3320 1225);
FORCEPROP 2 LAST ROOM E1S1_P12V_MAM_MAM_BOM1
J 0
(3325 1325);
DISPLAY 0.404255 (3325 1325);
FORCEPROP 1 LAST LOCATION R3976
J 0
(3320 1275);
DISPLAY 0.510638 (3320 1275);
FORCEPROP 1 LASTPIN (3275 1250) $PN 1
J 0
(3280 1212);
DISPLAY 0.510638 (3280 1212);
PAINT MONO (3280 1212);
FORCEPROP 1 LASTPIN (3275 1050) $PN 2
J 0
(3280 1060);
DISPLAY 0.510638 (3280 1060);
PAINT MONO (3280 1060);
FORCEPROP 2 LAST ROOM1 E1S1_P12V_MAM_TIC_BOM2
J 0
(3325 1375);
DISPLAY 1.021277 (3325 1375);
DISPLAY INVISIBLE (3325 1375);
FORCEPROP 2 LAST CDS_LIB pure_quanta
J 0
(3275 1150);
DISPLAY INVISIBLE (3275 1150);
FORCEPROP 1 LAST PATH I73
J 0
(3325 1325);
DISPLAY 0.978723 (3325 1325);
PAINT WHITE (3325 1325);
DISPLAY INVISIBLE (3325 1325);
FORCEPROP 0 LAST $SEC 1
J 0
(3325 1325);
DISPLAY 0.680851 (3325 1325);
PAINT MONO (3325 1325);
DISPLAY INVISIBLE (3325 1325);
FORCEPROP 0 LAST CDS_SEC 1
J 0
(3325 1325);
DISPLAY 1.021277 (3325 1325);
DISPLAY INVISIBLE (3325 1325);
FORCEADD VCCAUX15..1
(3475 1500);
FORCEPROP 3 LASTPIN (3475 1450) SIG_NAME P3V3_AUX\g
J 0
(3485 1460);
DISPLAY 0.659574 (3485 1460);
PAINT MONO (3485 1460);
DISPLAY INVISIBLE (3485 1460);
FORCEPROP 1 LAST HDL_POWER P3V3_AUX
J 1
(3475 1550);
DISPLAY 0.510638 (3475 1550);
PAINT GREEN (3475 1550);
FORCEPROP 2 LAST CDS_LIB logical_power
J 0
(3475 1500);
DISPLAY INVISIBLE (3475 1500);
FORCEPROP 1 LAST PATH I74
J 0
(3525 1525);
DISPLAY 0.872340 (3525 1525);
PAINT AQUA (3525 1525);
DISPLAY INVISIBLE (3525 1525);
FORCEADD Q_CAP..1
(3150 1825);
FORCEPROP 1 LAST PART_NUMBER CH4104K1B00
J 0
(3200 1725);
DISPLAY 0.510638 (3200 1725);
DISPLAY INVISIBLE (3200 1725);
FORCEPROP 1 LAST PACK_TYPE 0402
J 0
(3200 1675);
DISPLAY 0.510638 (3200 1675);
FORCEPROP 1 LAST VOLTAGE 25V
J 0
(3200 1825);
DISPLAY 0.510638 (3200 1825);
FORCEPROP 1 LAST MATERIAL X7R
J 0
(3200 1775);
DISPLAY 0.510638 (3200 1775);
FORCEPROP 1 LAST VALUE 0.1UF
J 0
(3200 1875);
DISPLAY 0.510638 (3200 1875);
FORCEPROP 1 LAST LOCATION PC2217
J 0
(3200 1925);
DISPLAY 0.510638 (3200 1925);
FORCEPROP 1 LASTPIN (3150 1925) $PN 1
J 0
(3160 1905);
DISPLAY 0.510638 (3160 1905);
PAINT MONO (3160 1905);
FORCEPROP 1 LASTPIN (3150 1725) $PN 2
J 0
(3160 1705);
DISPLAY 0.510638 (3160 1705);
PAINT MONO (3160 1705);
FORCEPROP 2 LAST CDS_LIB pure_quanta
J 0
(3150 1825);
DISPLAY INVISIBLE (3150 1825);
FORCEPROP 1 LAST TOLERANCE 10%
J 0
(3200 1775);
DISPLAY 0.978723 (3200 1775);
DISPLAY INVISIBLE (3200 1775);
FORCEPROP 1 LAST PATH I75
J 0
(3200 1975);
DISPLAY 0.978723 (3200 1975);
PAINT WHITE (3200 1975);
DISPLAY INVISIBLE (3200 1975);
FORCEPROP 0 LAST $SEC 1
J 0
(3200 1975);
DISPLAY 0.680851 (3200 1975);
PAINT MONO (3200 1975);
DISPLAY INVISIBLE (3200 1975);
FORCEPROP 0 LAST CDS_SEC 1
J 0
(3200 1975);
DISPLAY 1.021277 (3200 1975);
DISPLAY INVISIBLE (3200 1975);
FORCEADD Q_RES..2
(3700 1150);
FORCEPROP 1 LAST PART_NUMBER CS41002FB09
J 0
(3740 1025);
DISPLAY 0.510638 (3740 1025);
DISPLAY INVISIBLE (3740 1025);
FORCEPROP 1 LAST PACK_TYPE 0402LF
J 0
(3740 975);
DISPLAY 0.510638 (3740 975);
FORCEPROP 1 LAST VALUE 100K
J 0
(3745 1225);
DISPLAY 0.510638 (3745 1225);
FORCEPROP 1 LAST TOLERANCE 1%
J 0
(3745 1175);
DISPLAY 0.510638 (3745 1175);
FORCEPROP 1 LAST MATERIAL EMPTY
J 0
(3740 1075);
DISPLAY 0.510638 (3740 1075);
PAINT RED (3740 1075);
FORCEPROP 1 LAST WATTAGE 1/16W
J 0
(3740 1125);
DISPLAY 0.510638 (3740 1125);
FORCEPROP 2 LAST ROOM E1S1_P12V_MAM_MAM_BOM1
J 0
(3750 1325);
DISPLAY 0.404255 (3750 1325);
FORCEPROP 1 LAST LOCATION R3978
J 0
(3745 1275);
DISPLAY 0.510638 (3745 1275);
FORCEPROP 1 LASTPIN (3700 1250) $PN 1
J 0
(3705 1212);
DISPLAY 0.510638 (3705 1212);
PAINT MONO (3705 1212);
FORCEPROP 1 LASTPIN (3700 1050) $PN 2
J 0
(3705 1060);
DISPLAY 0.510638 (3705 1060);
PAINT MONO (3705 1060);
FORCEPROP 2 LAST ROOM1 E1S1_P12V_MAM_TIC_BOM2
J 0
(3750 1375);
DISPLAY 1.021277 (3750 1375);
DISPLAY INVISIBLE (3750 1375);
FORCEPROP 2 LAST CDS_LIB pure_quanta
J 0
(3700 1150);
DISPLAY INVISIBLE (3700 1150);
FORCEPROP 1 LAST PATH I76
J 0
(3750 1325);
DISPLAY 0.978723 (3750 1325);
PAINT WHITE (3750 1325);
DISPLAY INVISIBLE (3750 1325);
FORCEPROP 0 LAST $SEC 1
J 0
(3750 1325);
DISPLAY 0.680851 (3750 1325);
PAINT MONO (3750 1325);
DISPLAY INVISIBLE (3750 1325);
FORCEPROP 0 LAST CDS_SEC 1
J 0
(3750 1325);
DISPLAY 1.021277 (3750 1325);
DISPLAY INVISIBLE (3750 1325);
FORCEADD GND..1
(3975 1525);
FORCEPROP 3 LASTPIN (3975 1575) SIG_NAME GND\g
J 0
(3985 1585);
DISPLAY 0.659574 (3985 1585);
PAINT MONO (3985 1585);
DISPLAY INVISIBLE (3985 1585);
FORCEPROP 1 LAST SIZE 1B
J 0
(4050 1475);
DISPLAY 0.872340 (4050 1475);
PAINT GREEN (4050 1475);
DISPLAY INVISIBLE (4050 1475);
FORCEPROP 2 LAST CDS_LIB logical_power
J 0
(3975 1525);
DISPLAY INVISIBLE (3975 1525);
FORCEPROP 1 LAST HDL_POWER GND
J 0
(3975 1675);
DISPLAY 0.872340 (3975 1675);
PAINT GREEN (3975 1675);
DISPLAY INVISIBLE (3975 1675);
FORCEPROP 1 LAST PATH I77
J 0
(4050 1525);
DISPLAY 0.872340 (4050 1525);
PAINT AQUA (4050 1525);
DISPLAY INVISIBLE (4050 1525);
FORCEADD Q_CAP..1
(3575 1825);
FORCEPROP 1 LAST PART_NUMBER CH6103KEA03
J 0
(3625 1725);
DISPLAY 0.510638 (3625 1725);
DISPLAY INVISIBLE (3625 1725);
FORCEPROP 1 LAST VOLTAGE 16V
J 0
(3625 1825);
DISPLAY 0.510638 (3625 1825);
FORCEPROP 1 LAST MATERIAL X6S
J 0
(3625 1775);
DISPLAY 0.510638 (3625 1775);
FORCEPROP 1 LAST VALUE 10UF
J 0
(3625 1875);
DISPLAY 0.510638 (3625 1875);
FORCEPROP 1 LAST PACK_TYPE C0805
J 0
(3625 1675);
DISPLAY 0.510638 (3625 1675);
FORCEPROP 1 LAST LOCATION PC2219
J 0
(3625 1925);
DISPLAY 0.510638 (3625 1925);
FORCEPROP 2 LAST CDS_LIB pure_quanta
J 0
(3575 1825);
DISPLAY INVISIBLE (3575 1825);
FORCEPROP 1 LAST TOLERANCE 10%
J 0
(3625 1775);
DISPLAY 0.978723 (3625 1775);
DISPLAY INVISIBLE (3625 1775);
FORCEPROP 1 LAST PATH I78
J 0
(3625 1975);
DISPLAY 0.978723 (3625 1975);
PAINT WHITE (3625 1975);
DISPLAY INVISIBLE (3625 1975);
FORCEPROP 0 LAST $SEC 1
J 0
(3625 1975);
DISPLAY INVISIBLE (3625 1975);
FORCEPROP 0 LAST CDS_SEC 1
J 0
(3625 1975);
DISPLAY INVISIBLE (3625 1975);
FORCEPROP 1 LASTPIN (3575 1925) $PN 1
J 0
(3585 1905);
DISPLAY 0.787234 (3585 1905);
PAINT MONO (3585 1905);
DISPLAY INVISIBLE (3585 1905);
FORCEPROP 1 LASTPIN (3575 1725) $PN 2
J 0
(3585 1705);
DISPLAY 0.787234 (3585 1705);
PAINT MONO (3585 1705);
DISPLAY INVISIBLE (3585 1705);
FORCEADD Q_CAP..1
(3975 1825);
FORCEPROP 1 LAST PART_NUMBER CH6103KEA03
J 0
(4025 1725);
DISPLAY 0.638298 (4025 1725);
DISPLAY INVISIBLE (4025 1725);
FORCEPROP 1 LAST VOLTAGE 16V
J 0
(4025 1825);
DISPLAY 0.638298 (4025 1825);
FORCEPROP 1 LAST VALUE 10UF
J 0
(4025 1875);
DISPLAY 0.638298 (4025 1875);
FORCEPROP 1 LAST MATERIAL X6S
J 0
(4025 1775);
DISPLAY 0.638298 (4025 1775);
FORCEPROP 1 LAST PACK_TYPE C0805
J 0
(4025 1675);
DISPLAY 0.638298 (4025 1675);
FORCEPROP 1 LAST LOCATION PC2280
J 0
(4025 1925);
DISPLAY 0.680851 (4025 1925);
FORCEPROP 2 LAST CDS_LIB pure_quanta
J 0
(3975 1825);
DISPLAY INVISIBLE (3975 1825);
FORCEPROP 1 LAST TOLERANCE 10%
J 0
(3764 1785);
DISPLAY 0.787234 (3764 1785);
PAINT GREEN (3764 1785);
DISPLAY INVISIBLE (3764 1785);
FORCEPROP 1 LAST PATH I79
J 0
(4025 1975);
DISPLAY 0.978723 (4025 1975);
PAINT WHITE (4025 1975);
DISPLAY INVISIBLE (4025 1975);
FORCEPROP 0 LAST $SEC 1
J 0
(4025 1975);
DISPLAY INVISIBLE (4025 1975);
FORCEPROP 0 LAST CDS_SEC 1
J 0
(4025 1975);
DISPLAY INVISIBLE (4025 1975);
FORCEPROP 1 LASTPIN (3975 1925) $PN 1
J 0
(3985 1905);
DISPLAY 0.787234 (3985 1905);
PAINT MONO (3985 1905);
DISPLAY INVISIBLE (3985 1905);
FORCEPROP 1 LASTPIN (3975 1725) $PN 2
J 0
(3985 1705);
DISPLAY 0.787234 (3985 1705);
PAINT MONO (3985 1705);
DISPLAY INVISIBLE (3985 1705);
FORCEADD GND..1
(-3025 -450);
FORCEPROP 3 LASTPIN (-3025 -400) SIG_NAME GND\g
J 0
(-3015 -390);
DISPLAY 0.659574 (-3015 -390);
PAINT MONO (-3015 -390);
DISPLAY INVISIBLE (-3015 -390);
FORCEPROP 1 LAST HDL_POWER GND
J 0
(-3025 -300);
DISPLAY 0.872340 (-3025 -300);
PAINT GREEN (-3025 -300);
DISPLAY INVISIBLE (-3025 -300);
FORCEPROP 2 LAST CDS_LIB logical_power
J 0
(-3025 -450);
DISPLAY INVISIBLE (-3025 -450);
FORCEPROP 1 LAST SIZE 1B
J 0
(-2950 -500);
DISPLAY 0.872340 (-2950 -500);
PAINT GREEN (-2950 -500);
DISPLAY INVISIBLE (-2950 -500);
FORCEPROP 1 LAST PATH I8
J 0
(-2950 -450);
DISPLAY 0.872340 (-2950 -450);
PAINT AQUA (-2950 -450);
DISPLAY INVISIBLE (-2950 -450);
FORCEADD UNIVERSAL_POWER..1
R 2
(3975 2125);
FORCEPROP 3 LASTPIN (3975 2075) SIG_NAME P12V_E1S_0\g
J 0
(3985 2085);
DISPLAY 0.659574 (3985 2085);
PAINT MONO (3985 2085);
DISPLAY INVISIBLE (3985 2085);
FORCEPROP 1 LAST HDL_POWER P12V_E1S_0
J 1
(4000 2175);
DISPLAY 0.510638 (4000 2175);
PAINT GREEN (4000 2175);
FORCEPROP 2 LAST CDS_LIB logical_power
J 0
(3975 2125);
DISPLAY INVISIBLE (3975 2125);
FORCEPROP 1 LAST PATH I80
J 2
(3925 2150);
DISPLAY 0.872340 (3925 2150);
PAINT AQUA (3925 2150);
DISPLAY INVISIBLE (3925 2150);
FORCEADD OFFPAGE..2
(4225 475);
PAINT AQUA (4225 475);
FORCEPROP 2 LAST $XR0 250 
J 0
(4414 475);
DISPLAY 0.638298 (4414 475);
PAINT MONO (4414 475);
FORCEPROP 2 LAST CDS_LIB standard
J 0
(4225 475);
DISPLAY INVISIBLE (4225 475);
FORCEPROP 1 LAST OFFPAGE TRUE
J 0
(4550 350);
DISPLAY 0.872340 (4550 350);
PAINT AQUA (4550 350);
DISPLAY INVISIBLE (4550 350);
FORCEPROP 1 LAST COMMENT_BODY TRUE
J 0
(4180 380);
DISPLAY 0.872340 (4180 380);
PAINT GREEN (4180 380);
DISPLAY INVISIBLE (4180 380);
FORCEPROP 2 LAST PATH I81
J 0
(4425 525);
DISPLAY 1.021277 (4425 525);
DISPLAY INVISIBLE (4425 525);
FORCEADD OFFPAGE..2
(4225 700);
PAINT AQUA (4225 700);
FORCEPROP 2 LAST $XR0 250 
J 0
(4414 700);
DISPLAY 0.638298 (4414 700);
PAINT MONO (4414 700);
FORCEPROP 2 LAST CDS_LIB standard
J 0
(4225 700);
DISPLAY INVISIBLE (4225 700);
FORCEPROP 1 LAST OFFPAGE TRUE
J 0
(4550 575);
DISPLAY 0.872340 (4550 575);
PAINT AQUA (4550 575);
DISPLAY INVISIBLE (4550 575);
FORCEPROP 1 LAST COMMENT_BODY TRUE
J 0
(4180 605);
DISPLAY 0.872340 (4180 605);
PAINT GREEN (4180 605);
DISPLAY INVISIBLE (4180 605);
FORCEPROP 2 LAST PATH I82
J 0
(4425 750);
DISPLAY 1.021277 (4425 750);
DISPLAY INVISIBLE (4425 750);
FORCEADD OFFPAGE..2
(4225 900);
PAINT AQUA (4225 900);
FORCEPROP 2 LAST $XR1 216 
J 0
(4414 864);
DISPLAY 0.638298 (4414 864);
PAINT MONO (4414 864);
FORCEPROP 2 LAST $XR0 193 
J 0
(4414 900);
DISPLAY 0.638298 (4414 900);
PAINT MONO (4414 900);
FORCEPROP 2 LAST CDS_LIB standard
J 0
(4225 900);
DISPLAY INVISIBLE (4225 900);
FORCEPROP 1 LAST OFFPAGE TRUE
J 0
(4550 775);
DISPLAY 0.872340 (4550 775);
PAINT AQUA (4550 775);
DISPLAY INVISIBLE (4550 775);
FORCEPROP 1 LAST COMMENT_BODY TRUE
J 0
(4180 805);
DISPLAY 0.872340 (4180 805);
PAINT GREEN (4180 805);
DISPLAY INVISIBLE (4180 805);
FORCEPROP 2 LAST PATH I83
J 0
(4425 950);
DISPLAY 1.021277 (4425 950);
DISPLAY INVISIBLE (4425 950);
FORCEADD DIODE_TVS..1
R 1
(-925 1625);
FORCEPROP 1 LAST PART_NUMBER BCSMF14AZ01
J 0
(-870 1542);
DISPLAY 0.510638 (-870 1542);
PAINT GREEN (-870 1542);
DISPLAY INVISIBLE (-870 1542);
FORCEPROP 1 LAST MATERIAL IC
J 0
(-850 1500);
DISPLAY 0.510638 (-850 1500);
PAINT GREEN (-850 1500);
FORCEPROP 2 LAST VALUE SMF14A
J 0
(-875 1600);
DISPLAY 0.510638 (-875 1600);
PAINT SKYBLUE (-875 1600);
FORCEPROP 1 LAST LOCATION PD114
J 0
(-870 1667);
DISPLAY 0.510638 (-870 1667);
PAINT GREEN (-870 1667);
FORCEPROP 0 LASTPIN (-925 1475) $PN A
R 1
J 2
(-935 1465);
DISPLAY 0.510638 (-935 1465);
PAINT MONO (-935 1465);
FORCEPROP 0 LASTPIN (-925 1775) $PN C
R 1
J 0
(-935 1785);
DISPLAY 0.510638 (-935 1785);
PAINT MONO (-935 1785);
FORCEPROP 2 LAST CDS_LIB pure_quanta
J 0
(-925 1625);
DISPLAY INVISIBLE (-925 1625);
FORCEPROP 1 LAST CDS_LMAN_SYM_OUTLINE -100,50,100,-50
R 1
J 0
(-925 1625);
DISPLAY 0.468085 (-925 1625);
PAINT GREEN (-925 1625);
DISPLAY INVISIBLE (-925 1625);
FORCEPROP 1 LASTPIN (-925 1775) Pin_Length Short
R 1
J 0
(-915 1800);
DISPLAY 0.489362 (-915 1800);
PAINT MONO (-915 1800);
DISPLAY INVISIBLE (-915 1800);
FORCEPROP 1 LAST PIN_NAMES_ROTATE TRUE
R 1
J 0
(-925 1625);
DISPLAY 0.489362 (-925 1625);
PAINT GREEN (-925 1625);
DISPLAY INVISIBLE (-925 1625);
FORCEPROP 0 LAST PART_TYPE SMLF
J 0
(-825 1750);
DISPLAY 1.021277 (-825 1750);
DISPLAY INVISIBLE (-825 1750);
FORCEPROP 1 LAST PATH I84
R 1
J 0
(-875 1725);
DISPLAY 0.723404 (-875 1725);
PAINT GREEN (-875 1725);
DISPLAY INVISIBLE (-875 1725);
FORCEPROP 0 LAST $SEC 1
R 1
J 0
(-850 1700);
DISPLAY 0.680851 (-850 1700);
PAINT MONO (-850 1700);
DISPLAY INVISIBLE (-850 1700);
FORCEPROP 0 LAST CDS_SEC 1
R 1
J 0
(-850 1700);
DISPLAY 1.021277 (-850 1700);
DISPLAY INVISIBLE (-850 1700);
FORCEADD Q_RES..2
(-150 650);
FORCEPROP 1 LAST PART_NUMBER CS26802FB02
J 0
(-100 600);
DISPLAY 0.510638 (-100 600);
DISPLAY INVISIBLE (-100 600);
FORCEPROP 1 LAST MATERIAL EMPTY
J 0
(-100 625);
DISPLAY 0.510638 (-100 625);
PAINT RED (-100 625);
FORCEPROP 1 LAST TOLERANCE 1%
J 0
(-100 675);
DISPLAY 0.510638 (-100 675);
FORCEPROP 1 LAST VALUE 6.8K
J 0
(-100 700);
DISPLAY 0.510638 (-100 700);
FORCEPROP 1 LAST WATTAGE 1/16W
J 0
(-100 650);
DISPLAY 0.510638 (-100 650);
FORCEPROP 1 LAST PACK_TYPE 0402LF
J 0
(-100 575);
DISPLAY 0.510638 (-100 575);
FORCEPROP 2 LAST ROOM E1S1_P12V_MAM_MAM_BOM1
J 0
(-100 750);
DISPLAY 0.510638 (-100 750);
FORCEPROP 1 LAST LOCATION PR3961
J 0
(-100 725);
DISPLAY 0.510638 (-100 725);
FORCEPROP 1 LASTPIN (-150 750) $PN 1
J 0
(-145 712);
DISPLAY 0.510638 (-145 712);
PAINT MONO (-145 712);
FORCEPROP 1 LASTPIN (-150 550) $PN 2
J 0
(-145 560);
DISPLAY 0.510638 (-145 560);
PAINT MONO (-145 560);
FORCEPROP 2 LAST ROOM1 E1S1_P12V_MAM_TIC_BOM2
J 0
(-100 825);
DISPLAY 1.021277 (-100 825);
DISPLAY INVISIBLE (-100 825);
FORCEPROP 2 LAST CDS_LIB pure_quanta
J 0
(-150 650);
DISPLAY INVISIBLE (-150 650);
FORCEPROP 1 LAST PATH I85
J 0
(-100 825);
DISPLAY 0.978723 (-100 825);
PAINT WHITE (-100 825);
DISPLAY INVISIBLE (-100 825);
FORCEPROP 0 LAST $SEC 1
J 0
(-100 775);
DISPLAY 0.680851 (-100 775);
PAINT MONO (-100 775);
DISPLAY INVISIBLE (-100 775);
FORCEPROP 0 LAST CDS_SEC 1
J 0
(-100 775);
DISPLAY 1.021277 (-100 775);
DISPLAY INVISIBLE (-100 775);
FORCEADD Q_RES..2
(-3025 -225);
FORCEPROP 1 LAST PART_NUMBER CS24702JB10
J 0
(-2985 -400);
DISPLAY 0.638298 (-2985 -400);
DISPLAY INVISIBLE (-2985 -400);
FORCEPROP 1 LAST PACK_TYPE 0402LF
J 0
(-2985 -350);
DISPLAY 0.510638 (-2985 -350);
FORCEPROP 1 LAST WATTAGE 1/16W
J 0
(-2985 -250);
DISPLAY 0.510638 (-2985 -250);
FORCEPROP 1 LAST MATERIAL CHIP
J 0
(-2985 -300);
DISPLAY 0.510638 (-2985 -300);
FORCEPROP 1 LAST TOLERANCE 5%
J 0
(-2975 -200);
DISPLAY 0.510638 (-2975 -200);
FORCEPROP 1 LAST VALUE 4.7K
J 0
(-2980 -150);
DISPLAY 0.510638 (-2980 -150);
FORCEPROP 1 LAST $LOCATION R4073
J 0
(-2980 -100);
DISPLAY 0.510638 (-2980 -100);
FORCEPROP 1 LASTPIN (-3025 -125) $PN 1
J 0
(-3020 -163);
DISPLAY 0.510638 (-3020 -163);
PAINT MONO (-3020 -163);
FORCEPROP 1 LASTPIN (-3025 -325) $PN 2
J 0
(-3020 -315);
DISPLAY 0.510638 (-3020 -315);
PAINT MONO (-3020 -315);
FORCEPROP 2 LAST CDS_LIB pure_quanta
J 0
(-3025 -225);
DISPLAY INVISIBLE (-3025 -225);
FORCEPROP 1 LAST PATH I9
J 0
(-2975 -50);
DISPLAY 0.978723 (-2975 -50);
PAINT WHITE (-2975 -50);
DISPLAY INVISIBLE (-2975 -50);
FORCEPROP 0 LAST CDS_LOCATION R4073
J 0
(-2975 -50);
DISPLAY 1.021277 (-2975 -50);
DISPLAY INVISIBLE (-2975 -50);
FORCEPROP 0 LAST $SEC 1
J 0
(-2975 -50);
DISPLAY 0.680851 (-2975 -50);
PAINT MONO (-2975 -50);
DISPLAY INVISIBLE (-2975 -50);
FORCEPROP 0 LAST CDS_SEC 1
J 0
(-2975 -50);
DISPLAY 1.021277 (-2975 -50);
DISPLAY INVISIBLE (-2975 -50);
FORCEADD QUANTA_TITLE_BLOCK_C..1
(4625 -3375);
FORCEPROP 0 LAST CDS_CON_LAST_MODIFIED Fri Aug 25 14:03:06 2023
J 0
(2740 -3360);
PAINT MONO (2740 -3360);
DISPLAY INVISIBLE (2740 -3360);
FORCEPROP 2 LAST CUSTOM_TXT_CDS <XR_PAGE_TITLE>
J 0
(-3265 1875);
DISPLAY 0.638298 (-3265 1875);
PAINT PINK (-3265 1875);
DISPLAY INVISIBLE (-3265 1875);
FORCEPROP 2 LAST CUSTOM_TXT_CDS <CON_LAST_MODIFIED>
J 0
(2740 -3360);
DISPLAY 0.978723 (2740 -3360);
FORCEPROP 2 LAST CUSTOM_TXT_CDS <CON_PAGE_NUM> OF <CON_TOTAL_PAGES>
J 0
(4179 -3357);
DISPLAY 0.978723 (4179 -3357);
FORCEPROP 2 LAST CUSTOM_TXT_CDS <Q_REV>
J 0
(4441 -3272);
DISPLAY 1.212766 (4441 -3272);
FORCEPROP 2 LAST CUSTOM_TXT_CDS <Q_NUMBER>
J 0
(3222 -3272);
DISPLAY 1.212766 (3222 -3272);
FORCEPROP 2 LAST CUSTOM_TXT_CDS <NAME_2>
J 0
(1450 -3325);
FORCEPROP 2 LAST CUSTOM_TXT_CDS <NAME_1>
J 0
(1450 -3200);
FORCEPROP 2 LAST CUSTOM_TXT_CDS <Q_PROJ>
J 0
(2243 -3273);
DISPLAY 1.212766 (2243 -3273);
FORCEPROP 1 LAST Q_TITLE E1S_HSC
J 0
(-4641 -3324);
DISPLAY 2.446809 (-4641 -3324);
PAINT GREEN (-4641 -3324);
FORCEPROP 1 LAST Q_DEPT 
J 1
(862 -3326);
DISPLAY 1.957447 (862 -3326);
PAINT GREEN (862 -3326);
FORCEPROP 2 LAST CDS_XR_PAGE_TITLE CR-192 : @S9S_MB_2U_LIB.S9S_MB_2U(SCH_1):PAGE192
J 0
(-3265 1875);
DISPLAY 0.638298 (-3265 1875);
PAINT PINK (-3265 1875);
DISPLAY INVISIBLE (-3265 1875);
FORCEPROP 2 LAST PAGE_BORDER TRUE
J 0
(-3265 1875);
DISPLAY 0.638298 (-3265 1875);
PAINT PINK (-3265 1875);
DISPLAY INVISIBLE (-3265 1875);
FORCEPROP 2 LAST CDS_LIB pure_quanta
J 0
(4625 -3375);
PAINT MONO (4625 -3375);
DISPLAY INVISIBLE (4625 -3375);
FORCEPROP 1 LAST CDS_LMAN_SYM_OUTLINE -9475,6775,100,-125
J 0
(4625 -3375);
DISPLAY 0.468085 (4625 -3375);
PAINT GREEN (4625 -3375);
DISPLAY INVISIBLE (4625 -3375);
FORCEPROP 1 LAST COMMENT_BODY TRUE
J 0
(4637 -3388);
DISPLAY 0.978723 (4637 -3388);
PAINT GREEN (4637 -3388);
DISPLAY INVISIBLE (4637 -3388);
FORCEADD DNS..2
(-2525 125);
PAINT RED (-2525 125);
FORCEPROP 1 LAST COMMENT_BODY TRUE
R 1
J 0
(-2450 -100);
DISPLAY 0.872340 (-2450 -100);
PAINT GREEN (-2450 -100);
DISPLAY INVISIBLE (-2450 -100);
FORCEPROP 2 LAST CDS_LIB mstr_misc
J 0
(-2525 125);
DISPLAY INVISIBLE (-2525 125);
FORCEADD DNS..2
(-2500 750);
PAINT RED (-2500 750);
FORCEPROP 2 LAST CDS_LIB mstr_misc
J 0
(-2500 750);
DISPLAY INVISIBLE (-2500 750);
FORCEPROP 1 LAST COMMENT_BODY TRUE
R 1
J 0
(-2425 525);
DISPLAY 0.872340 (-2425 525);
PAINT GREEN (-2425 525);
DISPLAY INVISIBLE (-2425 525);
FORCEADD DNS..2
(-1825 550);
PAINT RED (-1825 550);
FORCEPROP 2 LAST CDS_LIB mstr_misc
J 0
(-1825 550);
DISPLAY INVISIBLE (-1825 550);
FORCEPROP 1 LAST COMMENT_BODY TRUE
R 1
J 0
(-1750 325);
DISPLAY 0.872340 (-1750 325);
PAINT GREEN (-1750 325);
DISPLAY INVISIBLE (-1750 325);
FORCEADD DNS..2
(-725 1000);
PAINT RED (-725 1000);
FORCEPROP 2 LAST CDS_LIB mstr_misc
J 0
(-725 1000);
DISPLAY INVISIBLE (-725 1000);
FORCEPROP 1 LAST COMMENT_BODY TRUE
R 1
J 0
(-650 775);
DISPLAY 0.872340 (-650 775);
PAINT GREEN (-650 775);
DISPLAY INVISIBLE (-650 775);
FORCEADD DNS..2
(-125 375);
PAINT RED (-125 375);
FORCEPROP 2 LAST CDS_LIB mstr_misc
J 0
(-125 375);
DISPLAY INVISIBLE (-125 375);
FORCEPROP 1 LAST COMMENT_BODY TRUE
R 1
J 0
(-50 150);
DISPLAY 0.872340 (-50 150);
PAINT GREEN (-50 150);
DISPLAY INVISIBLE (-50 150);
FORCEADD DNS..2
(-125 625);
PAINT RED (-125 625);
FORCEPROP 2 LAST CDS_LIB mstr_misc
J 0
(-125 625);
DISPLAY INVISIBLE (-125 625);
FORCEPROP 1 LAST COMMENT_BODY TRUE
R 1
J 0
(-50 400);
DISPLAY 0.872340 (-50 400);
PAINT GREEN (-50 400);
DISPLAY INVISIBLE (-50 400);
FORCEADD DNS..2
(-125 1325);
PAINT RED (-125 1325);
FORCEPROP 2 LAST CDS_LIB mstr_misc
J 0
(-125 1325);
DISPLAY INVISIBLE (-125 1325);
FORCEPROP 1 LAST COMMENT_BODY TRUE
R 1
J 0
(-50 1100);
DISPLAY 0.872340 (-50 1100);
PAINT GREEN (-50 1100);
DISPLAY INVISIBLE (-50 1100);
FORCEADD DNS..2
(2300 -1500);
PAINT RED (2300 -1500);
FORCEPROP 1 LAST COMMENT_BODY TRUE
R 1
J 0
(2375 -1725);
DISPLAY 0.872340 (2375 -1725);
PAINT GREEN (2375 -1725);
DISPLAY INVISIBLE (2375 -1725);
FORCEPROP 2 LAST CDS_LIB mstr_misc
J 0
(2300 -1500);
DISPLAY INVISIBLE (2300 -1500);
FORCEADD DNS..2
(425 900);
PAINT RED (425 900);
FORCEPROP 2 LAST CDS_LIB mstr_misc
J 0
(425 900);
DISPLAY INVISIBLE (425 900);
FORCEPROP 1 LAST COMMENT_BODY TRUE
R 1
J 0
(500 675);
DISPLAY 0.872340 (500 675);
PAINT GREEN (500 675);
DISPLAY INVISIBLE (500 675);
FORCEADD DNS..2
(725 375);
PAINT RED (725 375);
FORCEPROP 2 LAST CDS_LIB mstr_misc
J 0
(725 375);
DISPLAY INVISIBLE (725 375);
FORCEPROP 1 LAST COMMENT_BODY TRUE
R 1
J 0
(800 150);
DISPLAY 0.872340 (800 150);
PAINT GREEN (800 150);
DISPLAY INVISIBLE (800 150);
FORCEADD DNS..2
(200 1200);
PAINT RED (200 1200);
FORCEPROP 2 LAST CDS_LIB mstr_misc
J 0
(200 1200);
DISPLAY INVISIBLE (200 1200);
FORCEPROP 1 LAST COMMENT_BODY TRUE
R 1
J 0
(275 975);
DISPLAY 0.872340 (275 975);
PAINT GREEN (275 975);
DISPLAY INVISIBLE (275 975);
FORCEADD DNS..2
(200 1625);
PAINT RED (200 1625);
FORCEPROP 2 LAST CDS_LIB mstr_misc
J 0
(200 1625);
DISPLAY INVISIBLE (200 1625);
FORCEPROP 1 LAST COMMENT_BODY TRUE
R 1
J 0
(275 1400);
DISPLAY 0.872340 (275 1400);
PAINT GREEN (275 1400);
DISPLAY INVISIBLE (275 1400);
FORCEADD DNS..2
(1425 850);
PAINT RED (1425 850);
FORCEPROP 2 LAST CDS_LIB mstr_misc
J 0
(1425 850);
DISPLAY INVISIBLE (1425 850);
FORCEPROP 1 LAST COMMENT_BODY TRUE
R 1
J 0
(1500 625);
DISPLAY 0.872340 (1500 625);
PAINT GREEN (1500 625);
DISPLAY INVISIBLE (1500 625);
FORCEADD DNS..2
(2325 525);
PAINT RED (2325 525);
FORCEPROP 2 LAST CDS_LIB mstr_misc
J 0
(2325 525);
DISPLAY INVISIBLE (2325 525);
FORCEPROP 1 LAST COMMENT_BODY TRUE
R 1
J 0
(2400 300);
DISPLAY 0.872340 (2400 300);
PAINT GREEN (2400 300);
DISPLAY INVISIBLE (2400 300);
FORCEADD CAD_NOTE..1
(2850 175);
FORCEPROP 0 LAST S1 R3974/R3975 CO-LAYOUT
J 0
(2725 50);
DISPLAY 0.510638 (2725 50);
PAINT WHITE (2725 50);
FORCEPROP 2 LAST CDS_LIB logical_power
J 0
(2850 175);
DISPLAY INVISIBLE (2850 175);
FORCEPROP 1 LAST COMMENT_BODY TRUE
J 0
(2875 275);
DISPLAY 0.978723 (2875 275);
DISPLAY INVISIBLE (2875 275);
FORCEADD DNS..2
(3100 475);
PAINT RED (3100 475);
FORCEPROP 2 LAST CDS_LIB mstr_misc
J 0
(3100 475);
DISPLAY INVISIBLE (3100 475);
FORCEPROP 1 LAST COMMENT_BODY TRUE
R 1
J 0
(3175 250);
DISPLAY 0.872340 (3175 250);
PAINT GREEN (3175 250);
DISPLAY INVISIBLE (3175 250);
FORCEADD DNS..2
(2825 1000);
PAINT RED (2825 1000);
FORCEPROP 2 LAST CDS_LIB mstr_misc
J 0
(2825 1000);
DISPLAY INVISIBLE (2825 1000);
FORCEPROP 1 LAST COMMENT_BODY TRUE
R 1
J 0
(2900 775);
DISPLAY 0.872340 (2900 775);
PAINT GREEN (2900 775);
DISPLAY INVISIBLE (2900 775);
FORCEADD DNS..2
(3100 700);
PAINT RED (3100 700);
FORCEPROP 2 LAST CDS_LIB mstr_misc
J 0
(3100 700);
DISPLAY INVISIBLE (3100 700);
FORCEPROP 1 LAST COMMENT_BODY TRUE
R 1
J 0
(3175 475);
DISPLAY 0.872340 (3175 475);
PAINT GREEN (3175 475);
DISPLAY INVISIBLE (3175 475);
FORCEADD DNS..2
(2950 900);
PAINT RED (2950 900);
FORCEPROP 2 LAST CDS_LIB mstr_misc
J 0
(2950 900);
DISPLAY INVISIBLE (2950 900);
FORCEPROP 1 LAST COMMENT_BODY TRUE
R 1
J 0
(3025 675);
DISPLAY 0.872340 (3025 675);
PAINT GREEN (3025 675);
DISPLAY INVISIBLE (3025 675);
FORCEADD DNS..2
(2275 1225);
PAINT RED (2275 1225);
FORCEPROP 2 LAST CDS_LIB mstr_misc
J 0
(2275 1225);
DISPLAY INVISIBLE (2275 1225);
FORCEPROP 1 LAST COMMENT_BODY TRUE
R 1
J 0
(2350 1000);
DISPLAY 0.872340 (2350 1000);
PAINT GREEN (2350 1000);
DISPLAY INVISIBLE (2350 1000);
FORCEADD DNS..2
(2575 1225);
PAINT RED (2575 1225);
FORCEPROP 2 LAST CDS_LIB mstr_misc
J 0
(2575 1225);
DISPLAY INVISIBLE (2575 1225);
FORCEPROP 1 LAST COMMENT_BODY TRUE
R 1
J 0
(2650 1000);
DISPLAY 0.872340 (2650 1000);
PAINT GREEN (2650 1000);
DISPLAY INVISIBLE (2650 1000);
FORCEADD DNS..2
(3300 1150);
PAINT RED (3300 1150);
FORCEPROP 2 LAST CDS_LIB mstr_misc
J 0
(3300 1150);
DISPLAY INVISIBLE (3300 1150);
FORCEPROP 1 LAST COMMENT_BODY TRUE
R 1
J 0
(3375 925);
DISPLAY 0.872340 (3375 925);
PAINT GREEN (3375 925);
DISPLAY INVISIBLE (3375 925);
FORCEADD DNS..2
(3725 1150);
PAINT RED (3725 1150);
FORCEPROP 2 LAST CDS_LIB mstr_misc
J 0
(3725 1150);
DISPLAY INVISIBLE (3725 1150);
FORCEPROP 1 LAST COMMENT_BODY TRUE
R 1
J 0
(3800 925);
DISPLAY 0.872340 (3800 925);
PAINT GREEN (3800 925);
DISPLAY INVISIBLE (3800 925);
WIRE 16 -1 (-3150 -1575)(-3150 -1675);
WIRE 16 -1 (-475 -800)(-475 -875);
WIRE 16 -1 (-2525 950)(-2525 850);
WIRE 16 -1 (-725 1925)(-725 1850);
WIRE 16 -1 (3525 -1250)(3525 -1300);
WIRE 16 -1 (3775 -650)(3775 -700);
WIRE 16 -1 (3475 1450)(3475 1400);
WIRE 16 -1 (3975 2075)(3975 2025);
WIRE 16 -1 (-3150 -2575)(-3150 -2675);
WIRE 16 -1 (-2475 -2250)(-2475 -2300);
WIRE 16 -1 (-3025 -325)(-3025 -400);
WIRE 16 -1 (-2525 -50)(-2525 -150);
WIRE 16 -1 (-125 -2450)(-125 -2550);
WIRE 16 -1 (-475 -1200)(-475 -1325);
WIRE 16 -1 (-1825 325)(-1825 225);
WIRE 16 -1 (-150 275)(-150 175);
WIRE 16 -1 (-725 1300)(-725 1360);
WIRE 16 -1 (725 -2575)(725 -2525);
WIRE 16 -1 (200 -1825)(200 -1850);
WIRE 16 -1 (200 -1825)(325 -1825);
WIRE 16 -1 (200 -1625)(200 -1825);
WIRE 16 -1 (2200 -2450)(2200 -2375);
WIRE 16 -1 (3125 -1725)(3150 -1725);
WIRE 16 -1 (3775 -1150)(3775 -1075);
WIRE 16 -1 (175 900)(175 875);
WIRE 16 -1 (175 1100)(175 900);
WIRE 16 -1 (175 900)(300 900);
WIRE 16 -1 (700 150)(700 200);
WIRE 16 -1 (2175 275)(2175 350);
WIRE 16 -1 (2900 1000)(3050 1000);
WIRE 16 -1 (3975 1575)(3975 1650);
WIRE 16 -1 (-150 500)(-150 475);
WIRE 16 -1 (-150 550)(-150 500);
WIRE 16 -1 (-150 500)(150 500);
WIRE 16 -1 (150 500)(150 700);
WIRE 16 -1 (150 700)(1050 700);
FORCEPROP 2 LAST SIG_NAME P12V_E1S_OV_0
J 0
(590 710);
DISPLAY 0.510638 (590 710);
WIRE 16 -1 (-650 1000)(-150 1000);
WIRE 16 -1 (-150 1225)(-150 1000);
WIRE 16 -1 (-150 800)(-150 750);
WIRE 16 -1 (-150 800)(-150 1000);
WIRE 16 -1 (-150 800)(1050 800);
FORCEPROP 2 LAST SIG_NAME P12V_E1S_UV_0
J 0
(590 810);
DISPLAY 0.510638 (590 810);
WIRE 16 -1 (3175 475)(4175 475);
FORCEPROP 2 LAST SIG_NAME P12V_E1S_0_ISENSE_MAM_TIC
J 0
(3490 485);
DISPLAY 0.510638 (3490 485);
WIRE 16 -1 (3175 700)(4175 700);
FORCEPROP 2 LAST SIG_NAME P12V_E1S_0_ISENSE_MAM_MAM
J 0
(3490 710);
DISPLAY 0.510638 (3490 710);
WIRE 16 -1 (3975 1650)(3975 1725);
WIRE 16 -1 (3575 1650)(3575 1725);
WIRE 16 -1 (3975 1650)(3575 1650);
WIRE 16 -1 (3150 1650)(3150 1725);
WIRE 16 -1 (3575 1650)(3150 1650);
WIRE 16 -1 (2675 1650)(3150 1650);
WIRE 16 -1 (2675 1725)(2675 1650);
WIRE 16 -1 (3975 1925)(3975 2025);
WIRE 16 -1 (3575 2025)(3575 1925);
WIRE 16 -1 (3975 2025)(3575 2025);
WIRE 16 -1 (3150 1925)(3150 2025);
WIRE 16 -1 (3575 2025)(3150 2025);
WIRE 16 -1 (2675 2025)(2675 1975);
WIRE 16 -1 (3150 2025)(2675 2025);
WIRE 16 -1 (2575 1400)(2575 1350);
WIRE 16 -1 (2438 2025)(2675 2025);
WIRE 16 -1 (2438 2025)(2438 1400);
WIRE 16 -1 (2438 1400)(2575 1400);
WIRE 16 -1 (2250 1325)(2250 1400);
WIRE 16 -1 (2250 1400)(2438 1400);
WIRE 16 -1 (1850 1400)(2157 1400);
WIRE 16 -1 (2157 1400)(2250 1400);
WIRE 16 -1 (1850 1350)(2157 1350);
WIRE 16 -1 (2157 1350)(2157 1400);
WIRE 16 -1 (1850 1300)(2157 1300);
WIRE 16 -1 (2157 1300)(2157 1350);
WIRE 16 -1 (1850 1250)(2157 1250);
WIRE 16 -1 (2157 1250)(2157 1300);
WIRE 16 -1 (2157 1200)(1850 1200);
WIRE 16 -1 (2157 1200)(2157 1250);
WIRE 16 -1 (1850 1150)(2157 1150);
WIRE 16 -1 (2157 1150)(2157 1200);
WIRE 16 -1 (2157 1100)(2157 1150);
WIRE 16 -1 (1850 1100)(2157 1100);
WIRE 16 -1 (3275 1400)(3275 1250);
WIRE 16 -1 (3475 1400)(3275 1400);
WIRE 16 -1 (3700 1400)(3475 1400);
WIRE 16 -1 (3700 1400)(3700 1250);
WIRE 16 -1 (3700 1050)(3700 900);
FORCEPROP 2 LAST SIG_NAME HP_LVC3_E1S_0_HSC_PWRGD
J 0
(3540 910);
DISPLAY 0.510638 (3540 910);
WIRE 16 -1 (3700 900)(4175 900);
WIRE 16 -1 (3025 900)(3700 900);
WIRE 16 2175 (2675 350)(3400 350);
WIRE 16 2175 (3400 750)(3400 350);
WIRE 16 2175 (2675 750)(2675 350);
WIRE 16 2175 (2675 750)(3400 750);
WIRE 16 -1 (2625 475)(2975 475);
WIRE 16 -1 (2625 700)(2625 475);
WIRE 16 -1 (2625 700)(2975 700);
WIRE 16 -1 (1850 700)(2300 700);
WIRE 16 -1 (2300 700)(2625 700);
WIRE 16 -1 (2300 625)(2300 700);
FORCEPROP 2 LAST SIG_NAME P12V_E1S_SENSE_0
J 0
(1940 710);
DISPLAY 0.510638 (1940 710);
WIRE 16 -1 (2700 1000)(2575 1000);
WIRE 16 -1 (2575 1150)(2575 1000);
WIRE 16 -1 (2575 1000)(2250 1000);
WIRE 16 -1 (2250 1125)(2250 1000);
WIRE 16 -1 (1850 1000)(2250 1000);
FORCEPROP 2 LAST SIG_NAME P12V_E1S_GATE_0
J 0
(1940 1010);
DISPLAY 0.510638 (1940 1010);
WIRE 16 -1 (2300 425)(2300 350);
WIRE 16 -1 (1850 600)(2075 600);
WIRE 16 -1 (2175 350)(2300 350);
WIRE 16 -1 (2075 350)(2175 350);
WIRE 16 -1 (2075 600)(2075 350);
WIRE 16 -1 (1850 500)(2025 500);
WIRE 16 -1 (1850 450)(1975 450);
WIRE 16 -1 (2025 500)(2025 350);
WIRE 16 -1 (2075 350)(2025 350);
WIRE 16 -1 (1975 350)(2025 350);
WIRE 16 -1 (1975 450)(1975 350);
WIRE 16 -1 (1925 400)(1850 400);
WIRE 16 -1 (1925 350)(1975 350);
WIRE 16 -1 (1925 350)(1925 400);
WIRE 16 -1 (1850 900)(2825 900);
FORCEPROP 2 LAST SIG_NAME P12V_E1S_PWRGD_0
J 0
(1940 910);
DISPLAY 0.510638 (1940 910);
WIRE 16 -1 (3275 800)(3275 1050);
WIRE 16 -1 (1850 800)(3275 800);
FORCEPROP 2 LAST SIG_NAME P12V_E1S_FAULT_0
J 0
(1940 810);
DISPLAY 0.510638 (1940 810);
WIRE 16 -1 (700 200)(700 300);
WIRE 16 -1 (1025 200)(700 200);
WIRE 16 -1 (1025 500)(1025 200);
WIRE 16 -1 (1050 500)(1025 500);
WIRE 16 -1 (500 900)(1050 900);
FORCEPROP 2 LAST SIG_NAME P12V_E1S_REG_0
J 0
(565 910);
DISPLAY 0.510638 (565 910);
WIRE 16 -1 (-925 1850)(-925 1775);
WIRE 16 -1 (-725 1850)(-925 1850);
WIRE 16 -1 (-500 1850)(-725 1850);
WIRE 16 -1 (-500 1850)(-500 1725);
WIRE 16 -1 (-150 1850)(-150 1425);
WIRE 16 -1 (-500 1850)(-150 1850);
WIRE 16 -1 (-150 1850)(175 1850);
WIRE 16 -1 (175 1850)(175 1725);
WIRE 16 -1 (950 1850)(175 1850);
WIRE 16 -1 (950 1850)(950 1400);
WIRE 16 -1 (950 1400)(1050 1400);
WIRE 16 -1 (950 1400)(950 1350);
WIRE 16 -1 (950 1350)(1050 1350);
WIRE 16 -1 (950 1350)(950 1300);
WIRE 16 -1 (950 1300)(1050 1300);
WIRE 16 -1 (950 1300)(950 1250);
WIRE 16 -1 (950 1250)(1050 1250);
WIRE 16 -1 (950 1250)(950 1200);
WIRE 16 -1 (950 1200)(1050 1200);
WIRE 16 -1 (950 1200)(950 1150);
WIRE 16 -1 (950 1150)(1050 1150);
WIRE 16 -1 (950 1150)(950 1100);
WIRE 16 -1 (950 1100)(1050 1100);
WIRE 16 -1 (175 1425)(175 1300);
WIRE 16 -1 (175 1525)(175 1425);
WIRE 16 -1 (525 1425)(175 1425);
WIRE 16 -1 (525 1425)(525 1000);
WIRE 16 -1 (525 1000)(1050 1000);
FORCEPROP 2 LAST SIG_NAME P12V_E1S_VCC_0
J 0
(565 1010);
DISPLAY 0.510638 (565 1010);
WIRE 16 -1 (700 600)(700 500);
WIRE 16 -1 (1050 600)(700 600);
FORCEPROP 2 LAST SIG_NAME P12V_E1S_CB_0
J 0
(590 610);
DISPLAY 0.510638 (590 610);
WIRE 16 -1 (3775 -800)(3775 -700);
WIRE 16 -1 (3200 -800)(3200 -700);
WIRE 16 -1 (3775 -700)(3200 -700);
WIRE 16 -1 (2700 -700)(2700 -750);
WIRE 16 -1 (2700 -700)(3200 -700);
WIRE 16 -1 (2470 -700)(2700 -700);
WIRE 16 -1 (2550 -1325)(2550 -1400);
WIRE 16 -1 (2470 -1325)(2550 -1325);
WIRE 16 -1 (2470 -700)(2470 -1325);
WIRE 16 -1 (2275 -1400)(2275 -1325);
WIRE 16 -1 (2275 -1325)(2470 -1325);
WIRE 16 -1 (1875 -1325)(2182 -1325);
WIRE 16 -1 (2182 -1325)(2275 -1325);
WIRE 16 -1 (1875 -1375)(2182 -1375);
WIRE 16 -1 (2182 -1375)(2182 -1325);
WIRE 16 -1 (1875 -1425)(2182 -1425);
WIRE 16 -1 (2182 -1425)(2182 -1375);
WIRE 16 -1 (1875 -1475)(2182 -1475);
WIRE 16 -1 (2182 -1475)(2182 -1425);
WIRE 16 -1 (2182 -1525)(1875 -1525);
WIRE 16 -1 (2182 -1525)(2182 -1475);
WIRE 16 -1 (1875 -1575)(2182 -1575);
WIRE 16 -1 (2182 -1575)(2182 -1525);
WIRE 16 -1 (2182 -1625)(2182 -1575);
WIRE 16 -1 (1875 -1625)(2182 -1625);
WIRE 16 -1 (3725 -1625)(3725 -1825);
WIRE 16 -1 (3075 -1825)(3725 -1825);
FORCEPROP 2 LAST SIG_NAME TP_P3V3_E1S_PWRGD_0
J 0
(3440 -1815);
DISPLAY 0.574468 (3440 -1815);
WIRE 16 -1 (3725 -1300)(3725 -1425);
WIRE 16 -1 (3725 -1300)(3525 -1300);
WIRE 16 -1 (3325 -1300)(3325 -1425);
WIRE 16 -1 (3325 -1300)(3525 -1300);
WIRE 16 -1 (3775 -1075)(3775 -1000);
WIRE 16 -1 (3775 -1075)(3200 -1075);
WIRE 16 -1 (3200 -1075)(3200 -1000);
WIRE 16 -1 (2700 -1075)(3200 -1075);
WIRE 16 -1 (2700 -1000)(2700 -1075);
WIRE 16 -1 (2550 -1600)(2550 -1725);
WIRE 16 -1 (2925 -1725)(2550 -1725);
WIRE 16 -1 (2275 -1600)(2275 -1725);
WIRE 16 -1 (2550 -1725)(2275 -1725);
WIRE 16 -1 (1875 -1725)(2275 -1725);
FORCEPROP 2 LAST SIG_NAME P3V3_E1S_GATE_0
J 0
(1965 -1715);
DISPLAY 0.574468 (1965 -1715);
WIRE 16 -1 (2325 -2275)(2325 -2375);
WIRE 16 -1 (1875 -2125)(2100 -2125);
WIRE 16 -1 (2200 -2375)(2325 -2375);
WIRE 16 -1 (1875 -2225)(2050 -2225);
WIRE 16 -1 (2100 -2375)(2200 -2375);
WIRE 16 -1 (2100 -2125)(2100 -2375);
WIRE 16 -1 (2100 -2375)(2050 -2375);
WIRE 16 -1 (2050 -2225)(2050 -2375);
WIRE 16 -1 (1875 -2275)(2000 -2275);
WIRE 16 -1 (2000 -2275)(2000 -2375);
WIRE 16 -1 (2000 -2375)(2050 -2375);
WIRE 16 -1 (1950 -2375)(2000 -2375);
WIRE 16 -1 (1950 -2375)(1950 -2325);
WIRE 16 -1 (1950 -2325)(1875 -2325);
WIRE 16 -1 (1875 -1825)(2875 -1825);
FORCEPROP 2 LAST SIG_NAME P3V3_E1S_PWRGD_0
J 0
(1965 -1815);
DISPLAY 0.574468 (1965 -1815);
WIRE 16 -1 (2325 -2075)(2325 -2025);
FORCEPROP 2 LAST SIG_NAME P3V3_E1S_SENSE_0
J 0
(1965 -2015);
DISPLAY 0.574468 (1965 -2015);
WIRE 16 -1 (1875 -2025)(2325 -2025);
WIRE 16 -1 (3325 -1925)(3325 -1625);
WIRE 16 -1 (1875 -1925)(3325 -1925);
FORCEPROP 2 LAST SIG_NAME P3V3_E1S_FAULT_0
J 0
(1965 -1915);
DISPLAY 0.574468 (1965 -1915);
WIRE 16 -1 (-475 -875)(-475 -1000);
WIRE 16 -1 (-125 -875)(-125 -1250);
WIRE 16 -1 (-475 -875)(-125 -875);
WIRE 16 -1 (-125 -875)(200 -875);
WIRE 16 -1 (200 -875)(200 -1000);
WIRE 16 -1 (975 -875)(200 -875);
WIRE 16 -1 (975 -875)(975 -1325);
WIRE 16 -1 (975 -1325)(1075 -1325);
WIRE 16 -1 (975 -1325)(975 -1375);
WIRE 16 -1 (975 -1375)(1075 -1375);
WIRE 16 -1 (975 -1375)(975 -1425);
WIRE 16 -1 (975 -1425)(1075 -1425);
WIRE 16 -1 (975 -1425)(975 -1475);
WIRE 16 -1 (975 -1475)(1075 -1475);
WIRE 16 -1 (975 -1475)(975 -1525);
WIRE 16 -1 (975 -1525)(1075 -1525);
WIRE 16 -1 (975 -1525)(975 -1575);
WIRE 16 -1 (975 -1575)(1075 -1575);
WIRE 16 -1 (975 -1575)(975 -1625);
WIRE 16 -1 (975 -1625)(1075 -1625);
WIRE 16 -1 (525 -1825)(1075 -1825);
FORCEPROP 2 LAST SIG_NAME P3V3_E1S_REG_0
J 0
(590 -1815);
DISPLAY 0.574468 (590 -1815);
WIRE 16 -1 (200 -1300)(200 -1425);
WIRE 16 -1 (200 -1200)(200 -1300);
WIRE 16 -1 (550 -1300)(200 -1300);
WIRE 16 -1 (550 -1300)(550 -1725);
WIRE 16 -1 (550 -1725)(1075 -1725);
FORCEPROP 2 LAST SIG_NAME P3V3_E1S_VCC_0
J 0
(590 -1715);
DISPLAY 0.574468 (590 -1715);
WIRE 16 -1 (175 -2025)(1075 -2025);
FORCEPROP 2 LAST SIG_NAME P3V3_E1S_OV_0
J 0
(615 -2015);
DISPLAY 0.574468 (615 -2015);
WIRE 16 -1 (175 -2225)(175 -2025);
WIRE 16 -1 (-125 -2225)(-125 -2250);
WIRE 16 -1 (-125 -2175)(-125 -2225);
WIRE 16 -1 (-125 -2225)(175 -2225);
WIRE 16 -1 (725 -2525)(725 -2425);
WIRE 16 -1 (1050 -2525)(725 -2525);
WIRE 16 -1 (1050 -2225)(1050 -2525);
WIRE 16 -1 (1075 -2225)(1050 -2225);
WIRE 16 -1 (725 -2125)(725 -2225);
WIRE 16 -1 (1075 -2125)(725 -2125);
FORCEPROP 2 LAST SIG_NAME P3V3_E1S_CB_0
J 0
(615 -2115);
DISPLAY 0.574468 (615 -2115);
WIRE 16 -1 (-500 1360)(-500 1525);
WIRE 16 -1 (-500 1360)(-725 1360);
WIRE 16 -1 (-925 1360)(-725 1360);
WIRE 16 -1 (-925 1475)(-925 1360);
WIRE 16 -1 (-1825 1000)(-850 1000);
FORCEPROP 2 LAST SIG_NAME P12V_E1S_UV_0_R
J 0
(-1585 1010);
DISPLAY 0.510638 (-1585 1010);
WIRE 16 -1 (-1825 725)(-1825 1000);
WIRE 16 -1 (-2525 475)(-2075 475);
FORCEPROP 2 LAST SIG_NAME P12V_E1S_0_EN_G
J 0
(-2485 485);
DISPLAY 0.510638 (-2485 485);
WIRE 16 -1 (-2525 650)(-2525 475);
WIRE 16 -1 (-2525 350)(-2525 475);
WIRE 16 2175 (-4525 2325)(-2822 2325);
WIRE 16 2175 (-2822 3225)(-2822 2325);
WIRE 16 2175 (-4525 3225)(-4525 2325);
WIRE 16 2175 (-4525 3225)(-2822 3225);
WIRE 16 -1 (-3300 100)(-3025 100);
FORCEPROP 2 LAST SIG_NAME P12V_E1S_EN_0_R
J 0
(-3160 110);
DISPLAY 0.510638 (-3160 110);
WIRE 16 -1 (-3025 100)(-2775 100);
WIRE 16 -1 (-3025 -125)(-3025 100);
WIRE 16 -1 (-4400 100)(-4350 100);
WIRE 16 -1 (-3500 100)(-4350 100);
FORCEPROP 2 LAST SIG_NAME E1S_0_EN
J 0
(-4335 110);
DISPLAY 0.638298 (-4335 110);
WIRE 16 -1 (-4350 -2400)(-4200 -2400);
WIRE 16 -1 (-4350 -2400)(-4350 100);
WIRE 16 -1 (-125 -1925)(-125 -1975);
WIRE 16 -1 (-125 -1925)(1075 -1925);
FORCEPROP 2 LAST SIG_NAME P3V3_E1S_UV_0
J 0
(615 -1915);
DISPLAY 0.574468 (615 -1915);
WIRE 16 -1 (-125 -1925)(-125 -1725);
WIRE 16 -1 (-125 -1450)(-125 -1725);
WIRE 16 -1 (-500 -1725)(-125 -1725);
WIRE 16 -1 (-700 -1725)(-2475 -1725);
FORCEPROP 2 LAST SIG_NAME P3V3_E1S_UV_0_R
J 0
(-1735 -1715);
DISPLAY 0.574468 (-1735 -1715);
WIRE 16 -1 (-2475 -1850)(-2475 -1725);
WIRE 16 -1 (-3150 -2100)(-2725 -2100);
FORCEPROP 2 LAST SIG_NAME P3V3_E1S_0_EN_G
J 0
(-3110 -2090);
DISPLAY 0.595745 (-3110 -2090);
WIRE 16 -1 (-3150 -1875)(-3150 -2100);
WIRE 16 -1 (-3150 -2175)(-3150 -2100);
WIRE 16 -1 (-4000 -2425)(-4000 -2400);
WIRE 16 -1 (-4000 -2425)(-3400 -2425);
FORCEPROP 2 LAST SIG_NAME P3V3_E1S_EN_1_R
J 0
(-3835 -2415);
DISPLAY 0.595745 (-3835 -2415);
DOT 1 (3975 2025);
DOT 1 (3975 1650);
DOT 1 (3575 2025);
DOT 1 (3575 1650);
DOT 1 (3150 2025);
DOT 1 (3150 1650);
DOT 1 (3475 1400);
DOT 1 (3700 900);
DOT 1 (2675 2025);
DOT 1 (2438 1400);
DOT 1 (2250 1400);
DOT 1 (2157 1400);
DOT 1 (2157 1350);
DOT 1 (2157 1300);
DOT 1 (2157 1250);
DOT 1 (2157 1200);
DOT 1 (2157 1150);
DOT 1 (2575 1000);
DOT 1 (2625 700);
DOT 1 (2300 700);
DOT 1 (2250 1000);
DOT 1 (2175 350);
DOT 1 (2075 350);
DOT 1 (2025 350);
DOT 1 (1975 350);
DOT 1 (950 1400);
DOT 1 (950 1350);
DOT 1 (950 1300);
DOT 1 (950 1250);
DOT 1 (950 1200);
DOT 1 (950 1150);
DOT 1 (175 1850);
DOT 1 (175 1425);
DOT 1 (700 200);
DOT 1 (175 900);
DOT 1 (3775 -700);
DOT 1 (3200 -700);
DOT 1 (3775 -1075);
DOT 1 (3525 -1300);
DOT 1 (3200 -1075);
DOT 1 (2700 -700);
DOT 1 (2550 -1725);
DOT 1 (2470 -1325);
DOT 1 (2275 -1325);
DOT 1 (2182 -1375);
DOT 1 (2182 -1325);
DOT 1 (2182 -1425);
DOT 1 (2182 -1475);
DOT 1 (2182 -1525);
DOT 1 (2275 -1725);
DOT 1 (2182 -1575);
DOT 1 (2200 -2375);
DOT 1 (2100 -2375);
DOT 1 (2050 -2375);
DOT 1 (2000 -2375);
DOT 1 (975 -1575);
DOT 1 (975 -1525);
DOT 1 (975 -1475);
DOT 1 (975 -1425);
DOT 1 (975 -1375);
DOT 1 (975 -1325);
DOT 1 (200 -875);
DOT 1 (200 -1300);
DOT 1 (200 -1825);
DOT 1 (725 -2525);
DOT 1 (-150 1850);
DOT 1 (-500 1850);
DOT 1 (-725 1850);
DOT 1 (-725 1360);
DOT 1 (-150 1000);
DOT 1 (-150 800);
DOT 1 (-150 500);
DOT 1 (-2525 475);
DOT 1 (-3025 100);
DOT 1 (-4350 100);
DOT 1 (-125 -875);
DOT 1 (-475 -875);
DOT 1 (-125 -1725);
DOT 1 (-125 -1925);
DOT 1 (-125 -2225);
DOT 1 (-3150 -2100);
FORCENOTE
START UP TIME:8.21MS
(3350 775) 0;
DISPLAY LEFT (3350 775);
DISPLAY 0.510638 (3350 775);
PAINT WHITE (3350 775);
FORCENOTE
START UP TIME:3.94MS
(2775 -2125) 0;
DISPLAY LEFT (2775 -2125);
DISPLAY 1.021277 (2775 -2125);
PAINT WHITE (2775 -2125);
FORCENOTE
VIMON(MAX)= 1.604V @ IOUT=0.75A
(925 -2725) 0;
DISPLAY LEFT (925 -2725);
DISPLAY 1.021277 (925 -2725);
PAINT WHITE (925 -2725);
FORCENOTE
VIMON(MAX)= 1.641V @ IOUT=2.79A
(950 -150) 0;
DISPLAY LEFT (950 -150);
DISPLAY 0.510638 (950 -150);
PAINT WHITE (950 -150);
FORCENOTE
OVP: 14.91V
(-725 675) 0;
DISPLAY LEFT (-725 675);
DISPLAY 0.510638 (-725 675);
PAINT WHITE (-725 675);
FORCENOTE
UVP: 10.17V
(-725 750) 0;
DISPLAY LEFT (-725 750);
DISPLAY 0.510638 (-725 750);
PAINT WHITE (-725 750);
FORCENOTE
P12V_E1S_0
(-4475 3050) 0;
DISPLAY LEFT (-4475 3050);
DISPLAY 1.021277 (-4475 3050);
FORCENOTE
OCP=0.75A
(-4475 2525) 0;
DISPLAY LEFT (-4475 2525);
DISPLAY 1.021277 (-4475 2525);
FORCENOTE
IMAX=0.025A
(-4475 2600) 0;
DISPLAY LEFT (-4475 2600);
DISPLAY 1.021277 (-4475 2600);
FORCENOTE
P3V3_E1S_0_R
(-4475 2675) 0;
DISPLAY LEFT (-4475 2675);
DISPLAY 1.021277 (-4475 2675);
FORCENOTE
IMAX=2.083A
(-4475 2975) 0;
DISPLAY LEFT (-4475 2975);
DISPLAY 1.021277 (-4475 2975);
FORCENOTE
OCP=MAX*1.3=2.71A
(-4475 2900) 0;
DISPLAY LEFT (-4475 2900);
DISPLAY 1.021277 (-4475 2900);
FORCENOTE
DESIGN SPECIFICATION
(-4488 3144) 0;
DISPLAY LEFT (-4488 3144);
DISPLAY 1.170213 (-4488 3144);
FORCENOTE
UVP: 2.63V
(-650 -2025) 0;
DISPLAY LEFT (-650 -2025);
DISPLAY 1.021277 (-650 -2025);
PAINT WHITE (-650 -2025);
FORCENOTE
OVP: 3.89V
(-650 -2100) 0;
DISPLAY LEFT (-650 -2100);
DISPLAY 1.021277 (-650 -2100);
PAINT WHITE (-650 -2100);
QUIT
